FILE_TYPE = MACRO_DRAWING;
SET COLOR_WIRE YELLOW;
SET COLOR_PROP MONO;
SET COLOR_DOT WHITE;
SET COLOR_ARC YELLOW;
SET COLOR_BODY GREEN;
SET COLOR_NOTE MONO;
SET PROP_DISPLAY VALUE;
SET PAGE_NUMBER P51;
FORCEADD OFFPAGE..3
(1600 5200);
FORCEPROP 2 LAST $XR0 27 
J 0
(1814 5200);
DISPLAY 0.638298 (1814 5200);
PAINT MONO (1814 5200);
FORCEPROP 2 LAST $XR1 52 
J 0
(1904 5200);
DISPLAY 0.638298 (1904 5200);
PAINT MONO (1904 5200);
FORCEPROP 2 LAST CDS_LIB mstr_standard
J 0
(1600 5200);
DISPLAY 0.787234 (1600 5200);
PAINT MONO (1600 5200);
DISPLAY INVISIBLE (1600 5200);
FORCEPROP 1 LAST OFFPAGE TRUE
J 0
(1925 5075);
DISPLAY 0.936170 (1925 5075);
PAINT GREEN (1925 5075);
DISPLAY INVISIBLE (1925 5075);
FORCEPROP 1 LAST COMMENT_BODY TRUE
J 0
(1550 5100);
DISPLAY 0.936170 (1550 5100);
PAINT GREEN (1550 5100);
DISPLAY INVISIBLE (1550 5100);
FORCEPROP 2 LAST PATH I1
J 0
(1800 5275);
DISPLAY 0.787234 (1800 5275);
PAINT MONO (1800 5275);
DISPLAY INVISIBLE (1800 5275);
FORCEADD TAP..6
R 2
(700 5050);
FORCEPROP 3 LASTPIN (650 5050) SIG_NAME M_E_DQS_DP<16>
J 0
(660 5060);
DISPLAY 0.659574 (660 5060);
PAINT MONO (660 5060);
DISPLAY INVISIBLE (660 5060);
FORCEPROP 1 LASTPIN (650 5050) BN 16
J 2
(700 5060);
DISPLAY 0.617021 (700 5060);
PAINT PINK (700 5060);
FORCEPROP 2 LAST CDS_LIB mstr_standard
J 0
(700 5050);
DISPLAY 0.787234 (700 5050);
PAINT MONO (700 5050);
DISPLAY INVISIBLE (700 5050);
FORCEPROP 1 LAST BODY_TYPE PLUMBING
J 2
(700 5000);
DISPLAY 1.234043 (700 5000);
PAINT GREEN (700 5000);
DISPLAY INVISIBLE (700 5000);
FORCEPROP 1 LAST HDL_TAP TRUE
J 2
(375 4925);
DISPLAY 1.234043 (375 4925);
PAINT GREEN (375 4925);
DISPLAY INVISIBLE (375 4925);
FORCEPROP 1 LAST PATH I10
J 2
(700 5050);
DISPLAY 0.936170 (700 5050);
PAINT GREEN (700 5050);
DISPLAY INVISIBLE (700 5050);
FORCEADD TAP..6
R 2
(-1600 2250);
FORCEPROP 3 LASTPIN (-1650 2250) SIG_NAME M_E_DQ<11>
J 0
(-1640 2260);
DISPLAY 0.659574 (-1640 2260);
PAINT MONO (-1640 2260);
DISPLAY INVISIBLE (-1640 2260);
FORCEPROP 1 LASTPIN (-1650 2250) BN 11
J 2
(-1600 2260);
DISPLAY 0.617021 (-1600 2260);
PAINT PINK (-1600 2260);
FORCEPROP 2 LAST CDS_LIB mstr_standard
J 2
(-1600 2250);
DISPLAY 0.787234 (-1600 2250);
PAINT MONO (-1600 2250);
DISPLAY INVISIBLE (-1600 2250);
FORCEPROP 1 LAST BODY_TYPE PLUMBING
J 2
(-1600 2200);
DISPLAY 1.234043 (-1600 2200);
PAINT GREEN (-1600 2200);
DISPLAY INVISIBLE (-1600 2200);
FORCEPROP 1 LAST HDL_TAP TRUE
J 2
(-1925 2125);
DISPLAY 1.234043 (-1925 2125);
PAINT GREEN (-1925 2125);
DISPLAY INVISIBLE (-1925 2125);
FORCEPROP 1 LAST PATH I100
J 2
(-1600 2250);
DISPLAY 0.936170 (-1600 2250);
PAINT GREEN (-1600 2250);
DISPLAY INVISIBLE (-1600 2250);
FORCEADD TAP..6
R 2
(-1600 2200);
FORCEPROP 3 LASTPIN (-1650 2200) SIG_NAME M_E_DQ<8>
J 0
(-1640 2210);
DISPLAY 0.659574 (-1640 2210);
PAINT MONO (-1640 2210);
DISPLAY INVISIBLE (-1640 2210);
FORCEPROP 1 LASTPIN (-1650 2200) BN 8
J 2
(-1600 2210);
DISPLAY 0.617021 (-1600 2210);
PAINT PINK (-1600 2210);
FORCEPROP 2 LAST CDS_LIB mstr_standard
J 2
(-1600 2200);
DISPLAY 0.787234 (-1600 2200);
PAINT MONO (-1600 2200);
DISPLAY INVISIBLE (-1600 2200);
FORCEPROP 1 LAST BODY_TYPE PLUMBING
J 2
(-1600 2150);
DISPLAY 1.234043 (-1600 2150);
PAINT GREEN (-1600 2150);
DISPLAY INVISIBLE (-1600 2150);
FORCEPROP 1 LAST HDL_TAP TRUE
J 2
(-1925 2075);
DISPLAY 1.234043 (-1925 2075);
PAINT GREEN (-1925 2075);
DISPLAY INVISIBLE (-1925 2075);
FORCEPROP 1 LAST PATH I101
J 2
(-1600 2200);
DISPLAY 0.936170 (-1600 2200);
PAINT GREEN (-1600 2200);
DISPLAY INVISIBLE (-1600 2200);
FORCEADD TAP..6
R 2
(-1600 2100);
FORCEPROP 3 LASTPIN (-1650 2100) SIG_NAME M_E_DQ<6>
J 0
(-1640 2110);
DISPLAY 0.659574 (-1640 2110);
PAINT MONO (-1640 2110);
DISPLAY INVISIBLE (-1640 2110);
FORCEPROP 1 LASTPIN (-1650 2100) BN 6
J 2
(-1600 2110);
DISPLAY 0.617021 (-1600 2110);
PAINT PINK (-1600 2110);
FORCEPROP 2 LAST CDS_LIB mstr_standard
J 2
(-1600 2100);
DISPLAY 0.787234 (-1600 2100);
PAINT MONO (-1600 2100);
DISPLAY INVISIBLE (-1600 2100);
FORCEPROP 1 LAST BODY_TYPE PLUMBING
J 2
(-1600 2050);
DISPLAY 1.234043 (-1600 2050);
PAINT GREEN (-1600 2050);
DISPLAY INVISIBLE (-1600 2050);
FORCEPROP 1 LAST HDL_TAP TRUE
J 2
(-1925 1975);
DISPLAY 1.234043 (-1925 1975);
PAINT GREEN (-1925 1975);
DISPLAY INVISIBLE (-1925 1975);
FORCEPROP 1 LAST PATH I102
J 2
(-1600 2100);
DISPLAY 0.936170 (-1600 2100);
PAINT GREEN (-1600 2100);
DISPLAY INVISIBLE (-1600 2100);
FORCEADD TAP..6
R 2
(-1600 2150);
FORCEPROP 3 LASTPIN (-1650 2150) SIG_NAME M_E_DQ<9>
J 0
(-1640 2160);
DISPLAY 0.659574 (-1640 2160);
PAINT MONO (-1640 2160);
DISPLAY INVISIBLE (-1640 2160);
FORCEPROP 1 LASTPIN (-1650 2150) BN 9
J 2
(-1600 2160);
DISPLAY 0.617021 (-1600 2160);
PAINT PINK (-1600 2160);
FORCEPROP 2 LAST CDS_LIB mstr_standard
J 2
(-1600 2150);
DISPLAY 0.787234 (-1600 2150);
PAINT MONO (-1600 2150);
DISPLAY INVISIBLE (-1600 2150);
FORCEPROP 1 LAST BODY_TYPE PLUMBING
J 2
(-1600 2100);
DISPLAY 1.234043 (-1600 2100);
PAINT GREEN (-1600 2100);
DISPLAY INVISIBLE (-1600 2100);
FORCEPROP 1 LAST HDL_TAP TRUE
J 2
(-1925 2025);
DISPLAY 1.234043 (-1925 2025);
PAINT GREEN (-1925 2025);
DISPLAY INVISIBLE (-1925 2025);
FORCEPROP 1 LAST PATH I103
J 2
(-1600 2150);
DISPLAY 0.936170 (-1600 2150);
PAINT GREEN (-1600 2150);
DISPLAY INVISIBLE (-1600 2150);
FORCEADD TAP..6
R 2
(-1600 2050);
FORCEPROP 3 LASTPIN (-1650 2050) SIG_NAME M_E_DQ<7>
J 0
(-1640 2060);
DISPLAY 0.659574 (-1640 2060);
PAINT MONO (-1640 2060);
DISPLAY INVISIBLE (-1640 2060);
FORCEPROP 1 LASTPIN (-1650 2050) BN 7
J 2
(-1600 2060);
DISPLAY 0.617021 (-1600 2060);
PAINT PINK (-1600 2060);
FORCEPROP 2 LAST CDS_LIB mstr_standard
J 2
(-1600 2050);
DISPLAY 0.787234 (-1600 2050);
PAINT MONO (-1600 2050);
DISPLAY INVISIBLE (-1600 2050);
FORCEPROP 1 LAST BODY_TYPE PLUMBING
J 2
(-1600 2000);
DISPLAY 1.234043 (-1600 2000);
PAINT GREEN (-1600 2000);
DISPLAY INVISIBLE (-1600 2000);
FORCEPROP 1 LAST HDL_TAP TRUE
J 2
(-1925 1925);
DISPLAY 1.234043 (-1925 1925);
PAINT GREEN (-1925 1925);
DISPLAY INVISIBLE (-1925 1925);
FORCEPROP 1 LAST PATH I104
J 2
(-1600 2050);
DISPLAY 0.936170 (-1600 2050);
PAINT GREEN (-1600 2050);
DISPLAY INVISIBLE (-1600 2050);
FORCEADD TAP..6
R 2
(-1600 2000);
FORCEPROP 3 LASTPIN (-1650 2000) SIG_NAME M_E_DQ<4>
J 0
(-1640 2010);
DISPLAY 0.659574 (-1640 2010);
PAINT MONO (-1640 2010);
DISPLAY INVISIBLE (-1640 2010);
FORCEPROP 1 LASTPIN (-1650 2000) BN 4
J 2
(-1600 2010);
DISPLAY 0.617021 (-1600 2010);
PAINT PINK (-1600 2010);
FORCEPROP 2 LAST CDS_LIB mstr_standard
J 2
(-1600 2000);
DISPLAY 0.787234 (-1600 2000);
PAINT MONO (-1600 2000);
DISPLAY INVISIBLE (-1600 2000);
FORCEPROP 1 LAST BODY_TYPE PLUMBING
J 2
(-1600 1950);
DISPLAY 1.234043 (-1600 1950);
PAINT GREEN (-1600 1950);
DISPLAY INVISIBLE (-1600 1950);
FORCEPROP 1 LAST HDL_TAP TRUE
J 2
(-1925 1875);
DISPLAY 1.234043 (-1925 1875);
PAINT GREEN (-1925 1875);
DISPLAY INVISIBLE (-1925 1875);
FORCEPROP 1 LAST PATH I105
J 2
(-1600 2000);
DISPLAY 0.936170 (-1600 2000);
PAINT GREEN (-1600 2000);
DISPLAY INVISIBLE (-1600 2000);
FORCEADD TAP..6
R 2
(-1600 1900);
FORCEPROP 3 LASTPIN (-1650 1900) SIG_NAME M_E_DQ<2>
J 0
(-1640 1910);
DISPLAY 0.659574 (-1640 1910);
PAINT MONO (-1640 1910);
DISPLAY INVISIBLE (-1640 1910);
FORCEPROP 1 LASTPIN (-1650 1900) BN 2
J 2
(-1600 1910);
DISPLAY 0.617021 (-1600 1910);
PAINT PINK (-1600 1910);
FORCEPROP 2 LAST CDS_LIB mstr_standard
J 2
(-1600 1900);
DISPLAY 0.787234 (-1600 1900);
PAINT MONO (-1600 1900);
DISPLAY INVISIBLE (-1600 1900);
FORCEPROP 1 LAST BODY_TYPE PLUMBING
J 2
(-1600 1850);
DISPLAY 1.234043 (-1600 1850);
PAINT GREEN (-1600 1850);
DISPLAY INVISIBLE (-1600 1850);
FORCEPROP 1 LAST HDL_TAP TRUE
J 2
(-1925 1775);
DISPLAY 1.234043 (-1925 1775);
PAINT GREEN (-1925 1775);
DISPLAY INVISIBLE (-1925 1775);
FORCEPROP 1 LAST PATH I106
J 2
(-1600 1900);
DISPLAY 0.936170 (-1600 1900);
PAINT GREEN (-1600 1900);
DISPLAY INVISIBLE (-1600 1900);
FORCEADD TAP..6
R 2
(-1600 1950);
FORCEPROP 3 LASTPIN (-1650 1950) SIG_NAME M_E_DQ<5>
J 0
(-1640 1960);
DISPLAY 0.659574 (-1640 1960);
PAINT MONO (-1640 1960);
DISPLAY INVISIBLE (-1640 1960);
FORCEPROP 1 LASTPIN (-1650 1950) BN 5
J 2
(-1600 1960);
DISPLAY 0.617021 (-1600 1960);
PAINT PINK (-1600 1960);
FORCEPROP 2 LAST CDS_LIB mstr_standard
J 2
(-1600 1950);
DISPLAY 0.787234 (-1600 1950);
PAINT MONO (-1600 1950);
DISPLAY INVISIBLE (-1600 1950);
FORCEPROP 1 LAST BODY_TYPE PLUMBING
J 2
(-1600 1900);
DISPLAY 1.234043 (-1600 1900);
PAINT GREEN (-1600 1900);
DISPLAY INVISIBLE (-1600 1900);
FORCEPROP 1 LAST HDL_TAP TRUE
J 2
(-1925 1825);
DISPLAY 1.234043 (-1925 1825);
PAINT GREEN (-1925 1825);
DISPLAY INVISIBLE (-1925 1825);
FORCEPROP 1 LAST PATH I107
J 2
(-1600 1950);
DISPLAY 0.936170 (-1600 1950);
PAINT GREEN (-1600 1950);
DISPLAY INVISIBLE (-1600 1950);
FORCEADD TAP..6
R 2
(-1600 1800);
FORCEPROP 3 LASTPIN (-1650 1800) SIG_NAME M_E_DQ<0>
J 0
(-1640 1810);
DISPLAY 0.659574 (-1640 1810);
PAINT MONO (-1640 1810);
DISPLAY INVISIBLE (-1640 1810);
FORCEPROP 1 LASTPIN (-1650 1800) BN 0
J 2
(-1600 1810);
DISPLAY 0.617021 (-1600 1810);
PAINT PINK (-1600 1810);
FORCEPROP 2 LAST CDS_LIB mstr_standard
J 2
(-1600 1800);
DISPLAY 0.787234 (-1600 1800);
PAINT MONO (-1600 1800);
DISPLAY INVISIBLE (-1600 1800);
FORCEPROP 1 LAST BODY_TYPE PLUMBING
J 2
(-1600 1750);
DISPLAY 1.234043 (-1600 1750);
PAINT GREEN (-1600 1750);
DISPLAY INVISIBLE (-1600 1750);
FORCEPROP 1 LAST HDL_TAP TRUE
J 2
(-1925 1675);
DISPLAY 1.234043 (-1925 1675);
PAINT GREEN (-1925 1675);
DISPLAY INVISIBLE (-1925 1675);
FORCEPROP 1 LAST PATH I108
J 2
(-1600 1800);
DISPLAY 0.936170 (-1600 1800);
PAINT GREEN (-1600 1800);
DISPLAY INVISIBLE (-1600 1800);
FORCEADD TAP..6
R 2
(-1600 1850);
FORCEPROP 3 LASTPIN (-1650 1850) SIG_NAME M_E_DQ<3>
J 0
(-1640 1860);
DISPLAY 0.659574 (-1640 1860);
PAINT MONO (-1640 1860);
DISPLAY INVISIBLE (-1640 1860);
FORCEPROP 1 LASTPIN (-1650 1850) BN 3
J 2
(-1600 1860);
DISPLAY 0.617021 (-1600 1860);
PAINT PINK (-1600 1860);
FORCEPROP 2 LAST CDS_LIB mstr_standard
J 2
(-1600 1850);
DISPLAY 0.787234 (-1600 1850);
PAINT MONO (-1600 1850);
DISPLAY INVISIBLE (-1600 1850);
FORCEPROP 1 LAST BODY_TYPE PLUMBING
J 2
(-1600 1800);
DISPLAY 1.234043 (-1600 1800);
PAINT GREEN (-1600 1800);
DISPLAY INVISIBLE (-1600 1800);
FORCEPROP 1 LAST HDL_TAP TRUE
J 2
(-1925 1725);
DISPLAY 1.234043 (-1925 1725);
PAINT GREEN (-1925 1725);
DISPLAY INVISIBLE (-1925 1725);
FORCEPROP 1 LAST PATH I109
J 2
(-1600 1850);
DISPLAY 0.936170 (-1600 1850);
PAINT GREEN (-1600 1850);
DISPLAY INVISIBLE (-1600 1850);
FORCEADD TAP..6
R 2
(700 4950);
FORCEPROP 3 LASTPIN (650 4950) SIG_NAME M_E_DQS_DP<15>
J 0
(660 4960);
DISPLAY 0.659574 (660 4960);
PAINT MONO (660 4960);
DISPLAY INVISIBLE (660 4960);
FORCEPROP 1 LASTPIN (650 4950) BN 15
J 2
(700 4960);
DISPLAY 0.617021 (700 4960);
PAINT PINK (700 4960);
FORCEPROP 2 LAST CDS_LIB mstr_standard
J 0
(700 4950);
DISPLAY 0.787234 (700 4950);
PAINT MONO (700 4950);
DISPLAY INVISIBLE (700 4950);
FORCEPROP 1 LAST BODY_TYPE PLUMBING
J 2
(700 4900);
DISPLAY 1.234043 (700 4900);
PAINT GREEN (700 4900);
DISPLAY INVISIBLE (700 4900);
FORCEPROP 1 LAST HDL_TAP TRUE
J 2
(375 4825);
DISPLAY 1.234043 (375 4825);
PAINT GREEN (375 4825);
DISPLAY INVISIBLE (375 4825);
FORCEPROP 1 LAST PATH I11
J 2
(700 4950);
DISPLAY 0.936170 (700 4950);
PAINT GREEN (700 4950);
DISPLAY INVISIBLE (700 4950);
FORCEADD TAP..6
R 2
(-1600 1750);
FORCEPROP 3 LASTPIN (-1650 1750) SIG_NAME M_E_DQ<1>
J 0
(-1640 1760);
DISPLAY 0.659574 (-1640 1760);
PAINT MONO (-1640 1760);
DISPLAY INVISIBLE (-1640 1760);
FORCEPROP 1 LASTPIN (-1650 1750) BN 1
J 2
(-1600 1760);
DISPLAY 0.617021 (-1600 1760);
PAINT PINK (-1600 1760);
FORCEPROP 2 LAST CDS_LIB mstr_standard
J 2
(-1600 1750);
DISPLAY 0.787234 (-1600 1750);
PAINT MONO (-1600 1750);
DISPLAY INVISIBLE (-1600 1750);
FORCEPROP 1 LAST BODY_TYPE PLUMBING
J 2
(-1600 1700);
DISPLAY 1.234043 (-1600 1700);
PAINT GREEN (-1600 1700);
DISPLAY INVISIBLE (-1600 1700);
FORCEPROP 1 LAST HDL_TAP TRUE
J 2
(-1925 1625);
DISPLAY 1.234043 (-1925 1625);
PAINT GREEN (-1925 1625);
DISPLAY INVISIBLE (-1925 1625);
FORCEPROP 1 LAST PATH I110
J 2
(-1600 1750);
DISPLAY 0.936170 (-1600 1750);
PAINT GREEN (-1600 1750);
DISPLAY INVISIBLE (-1600 1750);
FORCEADD SCONN288_H44441004..1
(-2350 3250);
FORCEPROP 1 LAST LOCATION J4A2
J 0
(-2800 5150);
DISPLAY 0.617021 (-2800 5150);
PAINT AQUA (-2800 5150);
FORCEPROP 1 LAST PART_NUMBER H44441-004
J 0
(-2800 1250);
DISPLAY 0.617021 (-2800 1250);
PAINT BLUE (-2800 1250);
FORCEPROP 1 LAST MATERIAL SCONN
J 0
(-2800 5100);
DISPLAY 0.617021 (-2800 5100);
PAINT SKYBLUE (-2800 5100);
FORCEPROP 2 LASTPIN (-2850 1750) $PN 146
J 2
(-2860 1760);
DISPLAY 0.617021 (-2860 1760);
PAINT ORANGE (-2860 1760);
FORCEPROP 2 LASTPIN (-2850 2100) $PN 284
J 2
(-2860 2110);
DISPLAY 0.617021 (-2860 2110);
PAINT ORANGE (-2860 2110);
FORCEPROP 2 LASTPIN (-2850 1900) $PN 285
J 2
(-2860 1910);
DISPLAY 0.617021 (-2860 1910);
PAINT ORANGE (-2860 1910);
FORCEPROP 2 LASTPIN (-2850 1850) $PN 141
J 2
(-2860 1860);
DISPLAY 0.617021 (-2860 1860);
PAINT ORANGE (-2860 1860);
FORCEPROP 2 LASTPIN (-2850 1450) $PN 230
J 2
(-2860 1460);
DISPLAY 0.617021 (-2860 1460);
PAINT ORANGE (-2860 1460);
FORCEPROP 2 LASTPIN (-2850 2050) $PN 238
J 2
(-2860 2060);
DISPLAY 0.617021 (-2860 2060);
PAINT ORANGE (-2860 2060);
FORCEPROP 2 LASTPIN (-2850 2000) $PN 140
J 2
(-2860 2010);
DISPLAY 0.617021 (-2860 2010);
PAINT ORANGE (-2860 2010);
FORCEPROP 2 LASTPIN (-2850 1950) $PN 139
J 2
(-2860 1960);
DISPLAY 0.617021 (-2860 1960);
PAINT ORANGE (-2860 1960);
FORCEPROP 2 LASTPIN (-2850 3400) $PN 237
J 2
(-2860 3410);
DISPLAY 0.617021 (-2860 3410);
PAINT ORANGE (-2860 3410);
FORCEPROP 2 LASTPIN (-2850 3350) $PN 93
J 2
(-2860 3360);
DISPLAY 0.617021 (-2860 3360);
PAINT ORANGE (-2860 3360);
FORCEPROP 2 LASTPIN (-2850 3300) $PN 89
J 2
(-2860 3310);
DISPLAY 0.617021 (-2860 3310);
PAINT ORANGE (-2860 3310);
FORCEPROP 2 LASTPIN (-2850 3250) $PN 84
J 2
(-2860 3260);
DISPLAY 0.617021 (-2860 3260);
PAINT ORANGE (-2860 3260);
FORCEPROP 2 LASTPIN (-2850 1650) $PN 144
J 2
(-2860 1660);
DISPLAY 0.617021 (-2860 1660);
PAINT ORANGE (-2860 1660);
FORCEPROP 2 LASTPIN (-2850 1600) $PN 227
J 2
(-2860 1610);
DISPLAY 0.617021 (-2860 1610);
PAINT ORANGE (-2860 1610);
FORCEPROP 2 LASTPIN (-2850 1550) $PN 205
J 2
(-2860 1560);
DISPLAY 0.617021 (-2860 1560);
PAINT ORANGE (-2860 1560);
FORCEPROP 2 LASTPIN (-2850 2350) $PN 58
J 2
(-2860 2360);
DISPLAY 0.617021 (-2860 2360);
PAINT ORANGE (-2860 2360);
FORCEPROP 2 LASTPIN (-2850 2400) $PN 222
J 2
(-2860 2410);
DISPLAY 0.617021 (-2860 2410);
PAINT ORANGE (-2860 2410);
FORCEPROP 2 LASTPIN (-2850 3000) $PN 91
J 2
(-2860 3010);
DISPLAY 0.617021 (-2860 3010);
PAINT ORANGE (-2860 3010);
FORCEPROP 2 LASTPIN (-2850 2950) $PN 87
J 2
(-2860 2960);
DISPLAY 0.617021 (-2860 2960);
PAINT ORANGE (-2860 2960);
FORCEPROP 2 LASTPIN (-2850 2300) $PN 78
J 2
(-2860 2310);
DISPLAY 0.617021 (-2860 2310);
PAINT ORANGE (-2860 2310);
FORCEPROP 2 LASTPIN (-1850 4900) $PN 280
J 0
(-1840 4910);
DISPLAY 0.617021 (-1840 4910);
PAINT ORANGE (-1840 4910);
FORCEPROP 2 LASTPIN (-1850 4850) $PN 135
J 0
(-1840 4860);
DISPLAY 0.617021 (-1840 4860);
PAINT ORANGE (-1840 4860);
FORCEPROP 2 LASTPIN (-1850 4800) $PN 273
J 0
(-1840 4810);
DISPLAY 0.617021 (-1840 4810);
PAINT ORANGE (-1840 4810);
FORCEPROP 2 LASTPIN (-1850 4750) $PN 128
J 0
(-1840 4760);
DISPLAY 0.617021 (-1840 4760);
PAINT ORANGE (-1840 4760);
FORCEPROP 2 LASTPIN (-1850 4700) $PN 282
J 0
(-1840 4710);
DISPLAY 0.617021 (-1840 4710);
PAINT ORANGE (-1840 4710);
FORCEPROP 2 LASTPIN (-1850 4650) $PN 137
J 0
(-1840 4660);
DISPLAY 0.617021 (-1840 4660);
PAINT ORANGE (-1840 4660);
FORCEPROP 2 LASTPIN (-1850 4600) $PN 275
J 0
(-1840 4610);
DISPLAY 0.617021 (-1840 4610);
PAINT ORANGE (-1840 4610);
FORCEPROP 2 LASTPIN (-1850 4550) $PN 130
J 0
(-1840 4560);
DISPLAY 0.617021 (-1840 4560);
PAINT ORANGE (-1840 4560);
FORCEPROP 2 LASTPIN (-1850 4500) $PN 269
J 0
(-1840 4510);
DISPLAY 0.617021 (-1840 4510);
PAINT ORANGE (-1840 4510);
FORCEPROP 2 LASTPIN (-1850 4450) $PN 124
J 0
(-1840 4460);
DISPLAY 0.617021 (-1840 4460);
PAINT ORANGE (-1840 4460);
FORCEPROP 2 LASTPIN (-1850 4400) $PN 262
J 0
(-1840 4410);
DISPLAY 0.617021 (-1840 4410);
PAINT ORANGE (-1840 4410);
FORCEPROP 2 LASTPIN (-1850 4350) $PN 117
J 0
(-1840 4360);
DISPLAY 0.617021 (-1840 4360);
PAINT ORANGE (-1840 4360);
FORCEPROP 2 LASTPIN (-1850 4300) $PN 271
J 0
(-1840 4310);
DISPLAY 0.617021 (-1840 4310);
PAINT ORANGE (-1840 4310);
FORCEPROP 2 LASTPIN (-1850 4250) $PN 126
J 0
(-1840 4260);
DISPLAY 0.617021 (-1840 4260);
PAINT ORANGE (-1840 4260);
FORCEPROP 2 LASTPIN (-1850 4200) $PN 264
J 0
(-1840 4210);
DISPLAY 0.617021 (-1840 4210);
PAINT ORANGE (-1840 4210);
FORCEPROP 2 LASTPIN (-1850 4150) $PN 119
J 0
(-1840 4160);
DISPLAY 0.617021 (-1840 4160);
PAINT ORANGE (-1840 4160);
FORCEPROP 2 LASTPIN (-1850 4100) $PN 258
J 0
(-1840 4110);
DISPLAY 0.617021 (-1840 4110);
PAINT ORANGE (-1840 4110);
FORCEPROP 2 LASTPIN (-1850 4050) $PN 113
J 0
(-1840 4060);
DISPLAY 0.617021 (-1840 4060);
PAINT ORANGE (-1840 4060);
FORCEPROP 2 LASTPIN (-1850 4000) $PN 251
J 0
(-1840 4010);
DISPLAY 0.617021 (-1840 4010);
PAINT ORANGE (-1840 4010);
FORCEPROP 2 LASTPIN (-1850 3950) $PN 106
J 0
(-1840 3960);
DISPLAY 0.617021 (-1840 3960);
PAINT ORANGE (-1840 3960);
FORCEPROP 2 LASTPIN (-1850 3900) $PN 260
J 0
(-1840 3910);
DISPLAY 0.617021 (-1840 3910);
PAINT ORANGE (-1840 3910);
FORCEPROP 2 LASTPIN (-1850 3850) $PN 115
J 0
(-1840 3860);
DISPLAY 0.617021 (-1840 3860);
PAINT ORANGE (-1840 3860);
FORCEPROP 2 LASTPIN (-1850 3800) $PN 253
J 0
(-1840 3810);
DISPLAY 0.617021 (-1840 3810);
PAINT ORANGE (-1840 3810);
FORCEPROP 2 LASTPIN (-1850 3750) $PN 108
J 0
(-1840 3760);
DISPLAY 0.617021 (-1840 3760);
PAINT ORANGE (-1840 3760);
FORCEPROP 2 LASTPIN (-1850 3700) $PN 247
J 0
(-1840 3710);
DISPLAY 0.617021 (-1840 3710);
PAINT ORANGE (-1840 3710);
FORCEPROP 2 LASTPIN (-1850 3650) $PN 102
J 0
(-1840 3660);
DISPLAY 0.617021 (-1840 3660);
PAINT ORANGE (-1840 3660);
FORCEPROP 2 LASTPIN (-1850 3600) $PN 240
J 0
(-1840 3610);
DISPLAY 0.617021 (-1840 3610);
PAINT ORANGE (-1840 3610);
FORCEPROP 2 LASTPIN (-1850 3550) $PN 95
J 0
(-1840 3560);
DISPLAY 0.617021 (-1840 3560);
PAINT ORANGE (-1840 3560);
FORCEPROP 2 LASTPIN (-1850 3500) $PN 249
J 0
(-1840 3510);
DISPLAY 0.617021 (-1840 3510);
PAINT ORANGE (-1840 3510);
FORCEPROP 2 LASTPIN (-1850 3450) $PN 104
J 0
(-1840 3460);
DISPLAY 0.617021 (-1840 3460);
PAINT ORANGE (-1840 3460);
FORCEPROP 2 LASTPIN (-1850 3400) $PN 242
J 0
(-1840 3410);
DISPLAY 0.617021 (-1840 3410);
PAINT ORANGE (-1840 3410);
FORCEPROP 2 LASTPIN (-1850 3350) $PN 97
J 0
(-1840 3360);
DISPLAY 0.617021 (-1840 3360);
PAINT ORANGE (-1840 3360);
FORCEPROP 2 LASTPIN (-1850 3300) $PN 188
J 0
(-1840 3310);
DISPLAY 0.617021 (-1840 3310);
PAINT ORANGE (-1840 3310);
FORCEPROP 2 LASTPIN (-1850 3250) $PN 43
J 0
(-1840 3260);
DISPLAY 0.617021 (-1840 3260);
PAINT ORANGE (-1840 3260);
FORCEPROP 2 LASTPIN (-1850 3200) $PN 181
J 0
(-1840 3210);
DISPLAY 0.617021 (-1840 3210);
PAINT ORANGE (-1840 3210);
FORCEPROP 2 LASTPIN (-1850 3150) $PN 36
J 0
(-1840 3160);
DISPLAY 0.617021 (-1840 3160);
PAINT ORANGE (-1840 3160);
FORCEPROP 2 LASTPIN (-1850 3100) $PN 190
J 0
(-1840 3110);
DISPLAY 0.617021 (-1840 3110);
PAINT ORANGE (-1840 3110);
FORCEPROP 2 LASTPIN (-1850 3050) $PN 45
J 0
(-1840 3060);
DISPLAY 0.617021 (-1840 3060);
PAINT ORANGE (-1840 3060);
FORCEPROP 2 LASTPIN (-1850 3000) $PN 183
J 0
(-1840 3010);
DISPLAY 0.617021 (-1840 3010);
PAINT ORANGE (-1840 3010);
FORCEPROP 2 LASTPIN (-1850 2950) $PN 38
J 0
(-1840 2960);
DISPLAY 0.617021 (-1840 2960);
PAINT ORANGE (-1840 2960);
FORCEPROP 2 LASTPIN (-1850 2900) $PN 177
J 0
(-1840 2910);
DISPLAY 0.617021 (-1840 2910);
PAINT ORANGE (-1840 2910);
FORCEPROP 2 LASTPIN (-1850 2850) $PN 32
J 0
(-1840 2860);
DISPLAY 0.617021 (-1840 2860);
PAINT ORANGE (-1840 2860);
FORCEPROP 2 LASTPIN (-1850 2800) $PN 170
J 0
(-1840 2810);
DISPLAY 0.617021 (-1840 2810);
PAINT ORANGE (-1840 2810);
FORCEPROP 2 LASTPIN (-1850 2750) $PN 25
J 0
(-1840 2760);
DISPLAY 0.617021 (-1840 2760);
PAINT ORANGE (-1840 2760);
FORCEPROP 2 LASTPIN (-1850 2700) $PN 179
J 0
(-1840 2710);
DISPLAY 0.617021 (-1840 2710);
PAINT ORANGE (-1840 2710);
FORCEPROP 2 LASTPIN (-1850 2650) $PN 34
J 0
(-1840 2660);
DISPLAY 0.617021 (-1840 2660);
PAINT ORANGE (-1840 2660);
FORCEPROP 2 LASTPIN (-1850 2600) $PN 172
J 0
(-1840 2610);
DISPLAY 0.617021 (-1840 2610);
PAINT ORANGE (-1840 2610);
FORCEPROP 2 LASTPIN (-1850 2550) $PN 27
J 0
(-1840 2560);
DISPLAY 0.617021 (-1840 2560);
PAINT ORANGE (-1840 2560);
FORCEPROP 2 LASTPIN (-1850 2500) $PN 166
J 0
(-1840 2510);
DISPLAY 0.617021 (-1840 2510);
PAINT ORANGE (-1840 2510);
FORCEPROP 2 LASTPIN (-1850 2450) $PN 21
J 0
(-1840 2460);
DISPLAY 0.617021 (-1840 2460);
PAINT ORANGE (-1840 2460);
FORCEPROP 2 LASTPIN (-1850 2400) $PN 159
J 0
(-1840 2410);
DISPLAY 0.617021 (-1840 2410);
PAINT ORANGE (-1840 2410);
FORCEPROP 2 LASTPIN (-1850 2350) $PN 14
J 0
(-1840 2360);
DISPLAY 0.617021 (-1840 2360);
PAINT ORANGE (-1840 2360);
FORCEPROP 2 LASTPIN (-1850 2300) $PN 168
J 0
(-1840 2310);
DISPLAY 0.617021 (-1840 2310);
PAINT ORANGE (-1840 2310);
FORCEPROP 2 LASTPIN (-1850 2250) $PN 23
J 0
(-1840 2260);
DISPLAY 0.617021 (-1840 2260);
PAINT ORANGE (-1840 2260);
FORCEPROP 2 LASTPIN (-1850 2200) $PN 161
J 0
(-1840 2210);
DISPLAY 0.617021 (-1840 2210);
PAINT ORANGE (-1840 2210);
FORCEPROP 2 LASTPIN (-1850 2150) $PN 16
J 0
(-1840 2160);
DISPLAY 0.617021 (-1840 2160);
PAINT ORANGE (-1840 2160);
FORCEPROP 2 LASTPIN (-1850 2100) $PN 155
J 0
(-1840 2110);
DISPLAY 0.617021 (-1840 2110);
PAINT ORANGE (-1840 2110);
FORCEPROP 2 LASTPIN (-1850 2050) $PN 10
J 0
(-1840 2060);
DISPLAY 0.617021 (-1840 2060);
PAINT ORANGE (-1840 2060);
FORCEPROP 2 LASTPIN (-1850 2000) $PN 148
J 0
(-1840 2010);
DISPLAY 0.617021 (-1840 2010);
PAINT ORANGE (-1840 2010);
FORCEPROP 2 LASTPIN (-1850 1950) $PN 3
J 0
(-1840 1960);
DISPLAY 0.617021 (-1840 1960);
PAINT ORANGE (-1840 1960);
FORCEPROP 2 LASTPIN (-1850 1900) $PN 157
J 0
(-1840 1910);
DISPLAY 0.617021 (-1840 1910);
PAINT ORANGE (-1840 1910);
FORCEPROP 2 LASTPIN (-1850 1850) $PN 12
J 0
(-1840 1860);
DISPLAY 0.617021 (-1840 1860);
PAINT ORANGE (-1840 1860);
FORCEPROP 2 LASTPIN (-1850 1800) $PN 150
J 0
(-1840 1810);
DISPLAY 0.617021 (-1840 1810);
PAINT ORANGE (-1840 1810);
FORCEPROP 2 LASTPIN (-1850 1750) $PN 5
J 0
(-1840 1760);
DISPLAY 0.617021 (-1840 1760);
PAINT ORANGE (-1840 1760);
FORCEPROP 2 LASTPIN (-2850 3150) $PN 203
J 2
(-2860 3160);
DISPLAY 0.617021 (-2860 3160);
PAINT ORANGE (-2860 3160);
FORCEPROP 2 LASTPIN (-2850 3100) $PN 60
J 2
(-2860 3110);
DISPLAY 0.617021 (-2860 3110);
PAINT ORANGE (-2860 3110);
FORCEPROP 2 LASTPIN (-2850 3700) $PN 218
J 2
(-2860 3710);
DISPLAY 0.617021 (-2860 3710);
PAINT ORANGE (-2860 3710);
FORCEPROP 2 LASTPIN (-2850 3650) $PN 219
J 2
(-2860 3660);
DISPLAY 0.617021 (-2860 3660);
PAINT ORANGE (-2860 3660);
FORCEPROP 2 LASTPIN (-2850 3600) $PN 74
J 2
(-2860 3610);
DISPLAY 0.617021 (-2860 3610);
PAINT ORANGE (-2860 3610);
FORCEPROP 2 LASTPIN (-2850 3550) $PN 75
J 2
(-2860 3560);
DISPLAY 0.617021 (-2860 3560);
PAINT ORANGE (-2860 3560);
FORCEPROP 2 LASTPIN (-2850 2850) $PN 199
J 2
(-2860 2860);
DISPLAY 0.617021 (-2860 2860);
PAINT ORANGE (-2860 2860);
FORCEPROP 2 LASTPIN (-2850 2800) $PN 54
J 2
(-2860 2810);
DISPLAY 0.617021 (-2860 2810);
PAINT ORANGE (-2860 2810);
FORCEPROP 2 LASTPIN (-2850 2750) $PN 192
J 2
(-2860 2760);
DISPLAY 0.617021 (-2860 2760);
PAINT ORANGE (-2860 2760);
FORCEPROP 2 LASTPIN (-2850 2700) $PN 47
J 2
(-2860 2710);
DISPLAY 0.617021 (-2860 2710);
PAINT ORANGE (-2860 2710);
FORCEPROP 2 LASTPIN (-2850 2650) $PN 201
J 2
(-2860 2660);
DISPLAY 0.617021 (-2860 2660);
PAINT ORANGE (-2860 2660);
FORCEPROP 2 LASTPIN (-2850 2600) $PN 56
J 2
(-2860 2610);
DISPLAY 0.617021 (-2860 2610);
PAINT ORANGE (-2860 2610);
FORCEPROP 2 LASTPIN (-2850 2550) $PN 194
J 2
(-2860 2560);
DISPLAY 0.617021 (-2860 2560);
PAINT ORANGE (-2860 2560);
FORCEPROP 2 LASTPIN (-2850 2500) $PN 49
J 2
(-2860 2510);
DISPLAY 0.617021 (-2860 2510);
PAINT ORANGE (-2860 2510);
FORCEPROP 2 LASTPIN (-2850 3450) $PN 235
J 2
(-2860 3460);
DISPLAY 0.617021 (-2860 3460);
PAINT ORANGE (-2860 3460);
FORCEPROP 2 LASTPIN (-2850 3850) $PN 207
J 2
(-2860 3860);
DISPLAY 0.617021 (-2860 3860);
PAINT ORANGE (-2860 3860);
FORCEPROP 2 LASTPIN (-2850 3800) $PN 63
J 2
(-2860 3810);
DISPLAY 0.617021 (-2860 3810);
PAINT ORANGE (-2860 3810);
FORCEPROP 2 LASTPIN (-2850 3950) $PN 224
J 2
(-2860 3960);
DISPLAY 0.617021 (-2860 3960);
PAINT ORANGE (-2860 3960);
FORCEPROP 2 LASTPIN (-2850 3900) $PN 81
J 2
(-2860 3910);
DISPLAY 0.617021 (-2860 3910);
PAINT ORANGE (-2860 3910);
FORCEPROP 2 LASTPIN (-2850 2250) $PN 208
J 2
(-2860 2260);
DISPLAY 0.617021 (-2860 2260);
PAINT ORANGE (-2860 2260);
FORCEPROP 2 LASTPIN (-2850 2200) $PN 62
J 2
(-2860 2210);
DISPLAY 0.617021 (-2860 2210);
PAINT ORANGE (-2860 2210);
FORCEPROP 2 LASTPIN (-2850 4900) $PN 234
J 2
(-2860 4910);
DISPLAY 0.617021 (-2860 4910);
PAINT ORANGE (-2860 4910);
FORCEPROP 2 LASTPIN (-2850 4850) $PN 82
J 2
(-2860 4860);
DISPLAY 0.617021 (-2860 4860);
PAINT ORANGE (-2860 4860);
FORCEPROP 2 LASTPIN (-2850 4800) $PN 86
J 2
(-2860 4810);
DISPLAY 0.617021 (-2860 4810);
PAINT ORANGE (-2860 4810);
FORCEPROP 2 LASTPIN (-2850 4750) $PN 228
J 2
(-2860 4760);
DISPLAY 0.617021 (-2860 4760);
PAINT ORANGE (-2860 4760);
FORCEPROP 2 LASTPIN (-2850 4700) $PN 232
J 2
(-2860 4710);
DISPLAY 0.617021 (-2860 4710);
PAINT ORANGE (-2860 4710);
FORCEPROP 2 LASTPIN (-2850 4650) $PN 65
J 2
(-2860 4660);
DISPLAY 0.617021 (-2860 4660);
PAINT ORANGE (-2860 4660);
FORCEPROP 2 LASTPIN (-2850 4600) $PN 210
J 2
(-2860 4610);
DISPLAY 0.617021 (-2860 4610);
PAINT ORANGE (-2860 4610);
FORCEPROP 2 LASTPIN (-2850 4550) $PN 225
J 2
(-2860 4560);
DISPLAY 0.617021 (-2860 4560);
PAINT ORANGE (-2860 4560);
FORCEPROP 2 LASTPIN (-2850 4500) $PN 66
J 2
(-2860 4510);
DISPLAY 0.617021 (-2860 4510);
PAINT ORANGE (-2860 4510);
FORCEPROP 2 LASTPIN (-2850 4450) $PN 68
J 2
(-2860 4460);
DISPLAY 0.617021 (-2860 4460);
PAINT ORANGE (-2860 4460);
FORCEPROP 2 LASTPIN (-2850 4400) $PN 211
J 2
(-2860 4410);
DISPLAY 0.617021 (-2860 4410);
PAINT ORANGE (-2860 4410);
FORCEPROP 2 LASTPIN (-2850 4350) $PN 69
J 2
(-2860 4360);
DISPLAY 0.617021 (-2860 4360);
PAINT ORANGE (-2860 4360);
FORCEPROP 2 LASTPIN (-2850 4300) $PN 213
J 2
(-2860 4310);
DISPLAY 0.617021 (-2860 4310);
PAINT ORANGE (-2860 4310);
FORCEPROP 2 LASTPIN (-2850 4250) $PN 214
J 2
(-2860 4260);
DISPLAY 0.617021 (-2860 4260);
PAINT ORANGE (-2860 4260);
FORCEPROP 2 LASTPIN (-2850 4200) $PN 71
J 2
(-2860 4210);
DISPLAY 0.617021 (-2860 4210);
PAINT ORANGE (-2860 4210);
FORCEPROP 2 LASTPIN (-2850 4150) $PN 216
J 2
(-2860 4160);
DISPLAY 0.617021 (-2860 4160);
PAINT ORANGE (-2860 4160);
FORCEPROP 2 LASTPIN (-2850 4100) $PN 72
J 2
(-2860 4110);
DISPLAY 0.617021 (-2860 4110);
PAINT ORANGE (-2860 4110);
FORCEPROP 2 LASTPIN (-2850 4050) $PN 79
J 2
(-2860 4060);
DISPLAY 0.617021 (-2860 4060);
PAINT ORANGE (-2860 4060);
FORCEPROP 1 LAST PACK_TYPE PIP
J 0
(-2800 5200);
PAINT SKYBLUE (-2800 5200);
DISPLAY INVISIBLE (-2800 5200);
FORCEPROP 2 LAST BOM_COST MEM
J 0
(-2350 3250);
PAINT ORANGE (-2350 3250);
DISPLAY INVISIBLE (-2350 3250);
FORCEPROP 2 LAST CDS_LIB mstr_sconn
J 0
(-2350 3250);
PAINT ORANGE (-2350 3250);
DISPLAY INVISIBLE (-2350 3250);
FORCEPROP 2 LAST SEC_TYPE PIP
J 0
(-2800 5200);
DISPLAY 1.021277 (-2800 5200);
PAINT ORANGE (-2800 5200);
DISPLAY INVISIBLE (-2800 5200);
FORCEPROP 2 LAST SEC 1
J 0
(-2800 5200);
DISPLAY 0.680851 (-2800 5200);
PAINT MONO (-2800 5200);
DISPLAY INVISIBLE (-2800 5200);
FORCEPROP 2 LAST CDS_LOCATION J4A2
J 0
(-2800 5150);
DISPLAY 0.617021 (-2800 5150);
PAINT AQUA (-2800 5150);
DISPLAY INVISIBLE (-2800 5150);
FORCEPROP 1 LAST PATH I111
J 0
(-2350 5100);
PAINT GREEN (-2350 5100);
DISPLAY INVISIBLE (-2350 5100);
FORCEPROP 2 LAST ROOM DDR4_CH_E
J 0
(-2350 3250);
PAINT ORANGE (-2350 3250);
DISPLAY INVISIBLE (-2350 3250);
FORCEADD TAP..6
(-3100 4900);
FORCEPROP 3 LASTPIN (-3050 4900) SIG_NAME M_E_MA<17>
J 0
(-3040 4910);
DISPLAY 0.659574 (-3040 4910);
PAINT MONO (-3040 4910);
DISPLAY INVISIBLE (-3040 4910);
FORCEPROP 1 LASTPIN (-3050 4900) BN 17
J 0
(-3100 4910);
DISPLAY 0.617021 (-3100 4910);
PAINT PINK (-3100 4910);
FORCEPROP 2 LAST CDS_LIB mstr_standard
J 0
(-3100 4900);
DISPLAY 0.787234 (-3100 4900);
PAINT MONO (-3100 4900);
DISPLAY INVISIBLE (-3100 4900);
FORCEPROP 1 LAST BODY_TYPE PLUMBING
J 0
(-3100 4850);
DISPLAY 1.234043 (-3100 4850);
PAINT GREEN (-3100 4850);
DISPLAY INVISIBLE (-3100 4850);
FORCEPROP 1 LAST HDL_TAP TRUE
J 0
(-2775 4775);
DISPLAY 1.234043 (-2775 4775);
PAINT GREEN (-2775 4775);
DISPLAY INVISIBLE (-2775 4775);
FORCEPROP 1 LAST PATH I112
J 0
(-3100 4900);
DISPLAY 0.936170 (-3100 4900);
PAINT GREEN (-3100 4900);
DISPLAY INVISIBLE (-3100 4900);
FORCEADD TAP..6
(-3100 4850);
FORCEPROP 3 LASTPIN (-3050 4850) SIG_NAME M_E_MA<16>
J 0
(-3040 4860);
DISPLAY 0.659574 (-3040 4860);
PAINT MONO (-3040 4860);
DISPLAY INVISIBLE (-3040 4860);
FORCEPROP 1 LASTPIN (-3050 4850) BN 16
J 0
(-3100 4860);
DISPLAY 0.617021 (-3100 4860);
PAINT PINK (-3100 4860);
FORCEPROP 2 LAST CDS_LIB mstr_standard
J 2
(-3100 4850);
DISPLAY 0.787234 (-3100 4850);
PAINT MONO (-3100 4850);
DISPLAY INVISIBLE (-3100 4850);
FORCEPROP 1 LAST BODY_TYPE PLUMBING
J 0
(-3100 4800);
DISPLAY 1.234043 (-3100 4800);
PAINT GREEN (-3100 4800);
DISPLAY INVISIBLE (-3100 4800);
FORCEPROP 1 LAST HDL_TAP TRUE
J 0
(-2775 4725);
DISPLAY 1.234043 (-2775 4725);
PAINT GREEN (-2775 4725);
DISPLAY INVISIBLE (-2775 4725);
FORCEPROP 1 LAST PATH I113
J 0
(-3100 4850);
DISPLAY 0.936170 (-3100 4850);
PAINT GREEN (-3100 4850);
DISPLAY INVISIBLE (-3100 4850);
FORCEADD TAP..6
(-3100 4800);
FORCEPROP 3 LASTPIN (-3050 4800) SIG_NAME M_E_MA<15>
J 0
(-3040 4810);
DISPLAY 0.659574 (-3040 4810);
PAINT MONO (-3040 4810);
DISPLAY INVISIBLE (-3040 4810);
FORCEPROP 1 LASTPIN (-3050 4800) BN 15
J 0
(-3100 4810);
DISPLAY 0.617021 (-3100 4810);
PAINT PINK (-3100 4810);
FORCEPROP 2 LAST CDS_LIB mstr_standard
J 2
(-3100 4800);
DISPLAY 0.787234 (-3100 4800);
PAINT MONO (-3100 4800);
DISPLAY INVISIBLE (-3100 4800);
FORCEPROP 1 LAST BODY_TYPE PLUMBING
J 0
(-3100 4750);
DISPLAY 1.234043 (-3100 4750);
PAINT GREEN (-3100 4750);
DISPLAY INVISIBLE (-3100 4750);
FORCEPROP 1 LAST HDL_TAP TRUE
J 0
(-2775 4675);
DISPLAY 1.234043 (-2775 4675);
PAINT GREEN (-2775 4675);
DISPLAY INVISIBLE (-2775 4675);
FORCEPROP 1 LAST PATH I114
J 0
(-3100 4800);
DISPLAY 0.936170 (-3100 4800);
PAINT GREEN (-3100 4800);
DISPLAY INVISIBLE (-3100 4800);
FORCEADD TAP..6
(-3100 4750);
FORCEPROP 3 LASTPIN (-3050 4750) SIG_NAME M_E_MA<14>
J 0
(-3040 4760);
DISPLAY 0.659574 (-3040 4760);
PAINT MONO (-3040 4760);
DISPLAY INVISIBLE (-3040 4760);
FORCEPROP 1 LASTPIN (-3050 4750) BN 14
J 0
(-3100 4760);
DISPLAY 0.617021 (-3100 4760);
PAINT PINK (-3100 4760);
FORCEPROP 2 LAST CDS_LIB mstr_standard
J 2
(-3100 4750);
DISPLAY 0.787234 (-3100 4750);
PAINT MONO (-3100 4750);
DISPLAY INVISIBLE (-3100 4750);
FORCEPROP 1 LAST BODY_TYPE PLUMBING
J 0
(-3100 4700);
DISPLAY 1.234043 (-3100 4700);
PAINT GREEN (-3100 4700);
DISPLAY INVISIBLE (-3100 4700);
FORCEPROP 1 LAST HDL_TAP TRUE
J 0
(-2775 4625);
DISPLAY 1.234043 (-2775 4625);
PAINT GREEN (-2775 4625);
DISPLAY INVISIBLE (-2775 4625);
FORCEPROP 1 LAST PATH I115
J 0
(-3100 4750);
DISPLAY 0.936170 (-3100 4750);
PAINT GREEN (-3100 4750);
DISPLAY INVISIBLE (-3100 4750);
FORCEADD TAP..6
(-3100 4700);
FORCEPROP 3 LASTPIN (-3050 4700) SIG_NAME M_E_MA<13>
J 0
(-3040 4710);
DISPLAY 0.659574 (-3040 4710);
PAINT MONO (-3040 4710);
DISPLAY INVISIBLE (-3040 4710);
FORCEPROP 1 LASTPIN (-3050 4700) BN 13
J 0
(-3100 4710);
DISPLAY 0.617021 (-3100 4710);
PAINT PINK (-3100 4710);
FORCEPROP 2 LAST CDS_LIB mstr_standard
J 2
(-3100 4700);
DISPLAY 0.787234 (-3100 4700);
PAINT MONO (-3100 4700);
DISPLAY INVISIBLE (-3100 4700);
FORCEPROP 1 LAST BODY_TYPE PLUMBING
J 0
(-3100 4650);
DISPLAY 1.234043 (-3100 4650);
PAINT GREEN (-3100 4650);
DISPLAY INVISIBLE (-3100 4650);
FORCEPROP 1 LAST HDL_TAP TRUE
J 0
(-2775 4575);
DISPLAY 1.234043 (-2775 4575);
PAINT GREEN (-2775 4575);
DISPLAY INVISIBLE (-2775 4575);
FORCEPROP 1 LAST PATH I116
J 0
(-3100 4700);
DISPLAY 0.936170 (-3100 4700);
PAINT GREEN (-3100 4700);
DISPLAY INVISIBLE (-3100 4700);
FORCEADD TAP..6
(-3100 4650);
FORCEPROP 3 LASTPIN (-3050 4650) SIG_NAME M_E_MA<12>
J 0
(-3040 4660);
DISPLAY 0.659574 (-3040 4660);
PAINT MONO (-3040 4660);
DISPLAY INVISIBLE (-3040 4660);
FORCEPROP 1 LASTPIN (-3050 4650) BN 12
J 0
(-3100 4660);
DISPLAY 0.617021 (-3100 4660);
PAINT PINK (-3100 4660);
FORCEPROP 2 LAST CDS_LIB mstr_standard
J 2
(-3100 4650);
DISPLAY 0.787234 (-3100 4650);
PAINT MONO (-3100 4650);
DISPLAY INVISIBLE (-3100 4650);
FORCEPROP 1 LAST BODY_TYPE PLUMBING
J 0
(-3100 4600);
DISPLAY 1.234043 (-3100 4600);
PAINT GREEN (-3100 4600);
DISPLAY INVISIBLE (-3100 4600);
FORCEPROP 1 LAST HDL_TAP TRUE
J 0
(-2775 4525);
DISPLAY 1.234043 (-2775 4525);
PAINT GREEN (-2775 4525);
DISPLAY INVISIBLE (-2775 4525);
FORCEPROP 1 LAST PATH I117
J 0
(-3100 4650);
DISPLAY 0.936170 (-3100 4650);
PAINT GREEN (-3100 4650);
DISPLAY INVISIBLE (-3100 4650);
FORCEADD TAP..6
(-3100 4600);
FORCEPROP 3 LASTPIN (-3050 4600) SIG_NAME M_E_MA<11>
J 0
(-3040 4610);
DISPLAY 0.659574 (-3040 4610);
PAINT MONO (-3040 4610);
DISPLAY INVISIBLE (-3040 4610);
FORCEPROP 1 LASTPIN (-3050 4600) BN 11
J 0
(-3100 4610);
DISPLAY 0.617021 (-3100 4610);
PAINT PINK (-3100 4610);
FORCEPROP 2 LAST CDS_LIB mstr_standard
J 2
(-3100 4600);
DISPLAY 0.787234 (-3100 4600);
PAINT MONO (-3100 4600);
DISPLAY INVISIBLE (-3100 4600);
FORCEPROP 1 LAST BODY_TYPE PLUMBING
J 0
(-3100 4550);
DISPLAY 1.234043 (-3100 4550);
PAINT GREEN (-3100 4550);
DISPLAY INVISIBLE (-3100 4550);
FORCEPROP 1 LAST HDL_TAP TRUE
J 0
(-2775 4475);
DISPLAY 1.234043 (-2775 4475);
PAINT GREEN (-2775 4475);
DISPLAY INVISIBLE (-2775 4475);
FORCEPROP 1 LAST PATH I118
J 0
(-3100 4600);
DISPLAY 0.936170 (-3100 4600);
PAINT GREEN (-3100 4600);
DISPLAY INVISIBLE (-3100 4600);
FORCEADD TAP..6
(-3100 4550);
FORCEPROP 3 LASTPIN (-3050 4550) SIG_NAME M_E_MA<10>
J 0
(-3040 4560);
DISPLAY 0.659574 (-3040 4560);
PAINT MONO (-3040 4560);
DISPLAY INVISIBLE (-3040 4560);
FORCEPROP 1 LASTPIN (-3050 4550) BN 10
J 0
(-3100 4560);
DISPLAY 0.617021 (-3100 4560);
PAINT PINK (-3100 4560);
FORCEPROP 2 LAST CDS_LIB mstr_standard
J 2
(-3100 4550);
DISPLAY 0.787234 (-3100 4550);
PAINT MONO (-3100 4550);
DISPLAY INVISIBLE (-3100 4550);
FORCEPROP 1 LAST BODY_TYPE PLUMBING
J 0
(-3100 4500);
DISPLAY 1.234043 (-3100 4500);
PAINT GREEN (-3100 4500);
DISPLAY INVISIBLE (-3100 4500);
FORCEPROP 1 LAST HDL_TAP TRUE
J 0
(-2775 4425);
DISPLAY 1.234043 (-2775 4425);
PAINT GREEN (-2775 4425);
DISPLAY INVISIBLE (-2775 4425);
FORCEPROP 1 LAST PATH I119
J 0
(-3100 4550);
DISPLAY 0.936170 (-3100 4550);
PAINT GREEN (-3100 4550);
DISPLAY INVISIBLE (-3100 4550);
FORCEADD TAP..6
R 2
(700 4850);
FORCEPROP 3 LASTPIN (650 4850) SIG_NAME M_E_DQS_DP<14>
J 0
(660 4860);
DISPLAY 0.659574 (660 4860);
PAINT MONO (660 4860);
DISPLAY INVISIBLE (660 4860);
FORCEPROP 1 LASTPIN (650 4850) BN 14
J 2
(700 4860);
DISPLAY 0.617021 (700 4860);
PAINT PINK (700 4860);
FORCEPROP 2 LAST CDS_LIB mstr_standard
J 0
(700 4850);
DISPLAY 0.787234 (700 4850);
PAINT MONO (700 4850);
DISPLAY INVISIBLE (700 4850);
FORCEPROP 1 LAST BODY_TYPE PLUMBING
J 2
(700 4800);
DISPLAY 1.234043 (700 4800);
PAINT GREEN (700 4800);
DISPLAY INVISIBLE (700 4800);
FORCEPROP 1 LAST HDL_TAP TRUE
J 2
(375 4725);
DISPLAY 1.234043 (375 4725);
PAINT GREEN (375 4725);
DISPLAY INVISIBLE (375 4725);
FORCEPROP 1 LAST PATH I12
J 2
(700 4850);
DISPLAY 0.936170 (700 4850);
PAINT GREEN (700 4850);
DISPLAY INVISIBLE (700 4850);
FORCEADD TAP..6
(-3100 4500);
FORCEPROP 3 LASTPIN (-3050 4500) SIG_NAME M_E_MA<9>
J 0
(-3040 4510);
DISPLAY 0.659574 (-3040 4510);
PAINT MONO (-3040 4510);
DISPLAY INVISIBLE (-3040 4510);
FORCEPROP 1 LASTPIN (-3050 4500) BN 9
J 0
(-3100 4510);
DISPLAY 0.617021 (-3100 4510);
PAINT PINK (-3100 4510);
FORCEPROP 2 LAST CDS_LIB mstr_standard
J 2
(-3100 4500);
DISPLAY 0.787234 (-3100 4500);
PAINT MONO (-3100 4500);
DISPLAY INVISIBLE (-3100 4500);
FORCEPROP 1 LAST BODY_TYPE PLUMBING
J 0
(-3100 4450);
DISPLAY 1.234043 (-3100 4450);
PAINT GREEN (-3100 4450);
DISPLAY INVISIBLE (-3100 4450);
FORCEPROP 1 LAST HDL_TAP TRUE
J 0
(-2775 4375);
DISPLAY 1.234043 (-2775 4375);
PAINT GREEN (-2775 4375);
DISPLAY INVISIBLE (-2775 4375);
FORCEPROP 1 LAST PATH I120
J 0
(-3100 4500);
DISPLAY 0.936170 (-3100 4500);
PAINT GREEN (-3100 4500);
DISPLAY INVISIBLE (-3100 4500);
FORCEADD TAP..6
(-3100 4450);
FORCEPROP 3 LASTPIN (-3050 4450) SIG_NAME M_E_MA<8>
J 0
(-3040 4460);
DISPLAY 0.659574 (-3040 4460);
PAINT MONO (-3040 4460);
DISPLAY INVISIBLE (-3040 4460);
FORCEPROP 1 LASTPIN (-3050 4450) BN 8
J 0
(-3100 4460);
DISPLAY 0.617021 (-3100 4460);
PAINT PINK (-3100 4460);
FORCEPROP 2 LAST CDS_LIB mstr_standard
J 2
(-3100 4450);
DISPLAY 0.787234 (-3100 4450);
PAINT MONO (-3100 4450);
DISPLAY INVISIBLE (-3100 4450);
FORCEPROP 1 LAST BODY_TYPE PLUMBING
J 0
(-3100 4400);
DISPLAY 1.234043 (-3100 4400);
PAINT GREEN (-3100 4400);
DISPLAY INVISIBLE (-3100 4400);
FORCEPROP 1 LAST HDL_TAP TRUE
J 0
(-2775 4325);
DISPLAY 1.234043 (-2775 4325);
PAINT GREEN (-2775 4325);
DISPLAY INVISIBLE (-2775 4325);
FORCEPROP 1 LAST PATH I121
J 0
(-3100 4450);
DISPLAY 0.936170 (-3100 4450);
PAINT GREEN (-3100 4450);
DISPLAY INVISIBLE (-3100 4450);
FORCEADD TAP..6
(-3100 4400);
FORCEPROP 3 LASTPIN (-3050 4400) SIG_NAME M_E_MA<7>
J 0
(-3040 4410);
DISPLAY 0.659574 (-3040 4410);
PAINT MONO (-3040 4410);
DISPLAY INVISIBLE (-3040 4410);
FORCEPROP 1 LASTPIN (-3050 4400) BN 7
J 0
(-3100 4410);
DISPLAY 0.617021 (-3100 4410);
PAINT PINK (-3100 4410);
FORCEPROP 2 LAST CDS_LIB mstr_standard
J 2
(-3100 4400);
DISPLAY 0.787234 (-3100 4400);
PAINT MONO (-3100 4400);
DISPLAY INVISIBLE (-3100 4400);
FORCEPROP 1 LAST BODY_TYPE PLUMBING
J 0
(-3100 4350);
DISPLAY 1.234043 (-3100 4350);
PAINT GREEN (-3100 4350);
DISPLAY INVISIBLE (-3100 4350);
FORCEPROP 1 LAST HDL_TAP TRUE
J 0
(-2775 4275);
DISPLAY 1.234043 (-2775 4275);
PAINT GREEN (-2775 4275);
DISPLAY INVISIBLE (-2775 4275);
FORCEPROP 1 LAST PATH I122
J 0
(-3100 4400);
DISPLAY 0.936170 (-3100 4400);
PAINT GREEN (-3100 4400);
DISPLAY INVISIBLE (-3100 4400);
FORCEADD TAP..6
(-3100 4350);
FORCEPROP 3 LASTPIN (-3050 4350) SIG_NAME M_E_MA<6>
J 0
(-3040 4360);
DISPLAY 0.659574 (-3040 4360);
PAINT MONO (-3040 4360);
DISPLAY INVISIBLE (-3040 4360);
FORCEPROP 1 LASTPIN (-3050 4350) BN 6
J 0
(-3100 4360);
DISPLAY 0.617021 (-3100 4360);
PAINT PINK (-3100 4360);
FORCEPROP 2 LAST CDS_LIB mstr_standard
J 2
(-3100 4350);
DISPLAY 0.787234 (-3100 4350);
PAINT MONO (-3100 4350);
DISPLAY INVISIBLE (-3100 4350);
FORCEPROP 1 LAST BODY_TYPE PLUMBING
J 0
(-3100 4300);
DISPLAY 1.234043 (-3100 4300);
PAINT GREEN (-3100 4300);
DISPLAY INVISIBLE (-3100 4300);
FORCEPROP 1 LAST HDL_TAP TRUE
J 0
(-2775 4225);
DISPLAY 1.234043 (-2775 4225);
PAINT GREEN (-2775 4225);
DISPLAY INVISIBLE (-2775 4225);
FORCEPROP 1 LAST PATH I123
J 0
(-3100 4350);
DISPLAY 0.936170 (-3100 4350);
PAINT GREEN (-3100 4350);
DISPLAY INVISIBLE (-3100 4350);
FORCEADD TAP..6
(-3100 4300);
FORCEPROP 3 LASTPIN (-3050 4300) SIG_NAME M_E_MA<5>
J 0
(-3040 4310);
DISPLAY 0.659574 (-3040 4310);
PAINT MONO (-3040 4310);
DISPLAY INVISIBLE (-3040 4310);
FORCEPROP 1 LASTPIN (-3050 4300) BN 5
J 0
(-3100 4310);
DISPLAY 0.617021 (-3100 4310);
PAINT PINK (-3100 4310);
FORCEPROP 2 LAST CDS_LIB mstr_standard
J 2
(-3100 4300);
DISPLAY 0.787234 (-3100 4300);
PAINT MONO (-3100 4300);
DISPLAY INVISIBLE (-3100 4300);
FORCEPROP 1 LAST BODY_TYPE PLUMBING
J 0
(-3100 4250);
DISPLAY 1.234043 (-3100 4250);
PAINT GREEN (-3100 4250);
DISPLAY INVISIBLE (-3100 4250);
FORCEPROP 1 LAST HDL_TAP TRUE
J 0
(-2775 4175);
DISPLAY 1.234043 (-2775 4175);
PAINT GREEN (-2775 4175);
DISPLAY INVISIBLE (-2775 4175);
FORCEPROP 1 LAST PATH I124
J 0
(-3100 4300);
DISPLAY 0.936170 (-3100 4300);
PAINT GREEN (-3100 4300);
DISPLAY INVISIBLE (-3100 4300);
FORCEADD TAP..6
(-3100 4250);
FORCEPROP 3 LASTPIN (-3050 4250) SIG_NAME M_E_MA<4>
J 0
(-3040 4260);
DISPLAY 0.659574 (-3040 4260);
PAINT MONO (-3040 4260);
DISPLAY INVISIBLE (-3040 4260);
FORCEPROP 1 LASTPIN (-3050 4250) BN 4
J 0
(-3100 4260);
DISPLAY 0.617021 (-3100 4260);
PAINT PINK (-3100 4260);
FORCEPROP 2 LAST CDS_LIB mstr_standard
J 2
(-3100 4250);
DISPLAY 0.787234 (-3100 4250);
PAINT MONO (-3100 4250);
DISPLAY INVISIBLE (-3100 4250);
FORCEPROP 1 LAST BODY_TYPE PLUMBING
J 0
(-3100 4200);
DISPLAY 1.234043 (-3100 4200);
PAINT GREEN (-3100 4200);
DISPLAY INVISIBLE (-3100 4200);
FORCEPROP 1 LAST HDL_TAP TRUE
J 0
(-2775 4125);
DISPLAY 1.234043 (-2775 4125);
PAINT GREEN (-2775 4125);
DISPLAY INVISIBLE (-2775 4125);
FORCEPROP 1 LAST PATH I125
J 0
(-3100 4250);
DISPLAY 0.936170 (-3100 4250);
PAINT GREEN (-3100 4250);
DISPLAY INVISIBLE (-3100 4250);
FORCEADD TAP..6
(-3100 4200);
FORCEPROP 3 LASTPIN (-3050 4200) SIG_NAME M_E_MA<3>
J 0
(-3040 4210);
DISPLAY 0.659574 (-3040 4210);
PAINT MONO (-3040 4210);
DISPLAY INVISIBLE (-3040 4210);
FORCEPROP 1 LASTPIN (-3050 4200) BN 3
J 0
(-3100 4210);
DISPLAY 0.617021 (-3100 4210);
PAINT PINK (-3100 4210);
FORCEPROP 2 LAST CDS_LIB mstr_standard
J 2
(-3100 4200);
DISPLAY 0.787234 (-3100 4200);
PAINT MONO (-3100 4200);
DISPLAY INVISIBLE (-3100 4200);
FORCEPROP 1 LAST BODY_TYPE PLUMBING
J 0
(-3100 4150);
DISPLAY 1.234043 (-3100 4150);
PAINT GREEN (-3100 4150);
DISPLAY INVISIBLE (-3100 4150);
FORCEPROP 1 LAST HDL_TAP TRUE
J 0
(-2775 4075);
DISPLAY 1.234043 (-2775 4075);
PAINT GREEN (-2775 4075);
DISPLAY INVISIBLE (-2775 4075);
FORCEPROP 1 LAST PATH I126
J 0
(-3100 4200);
DISPLAY 0.936170 (-3100 4200);
PAINT GREEN (-3100 4200);
DISPLAY INVISIBLE (-3100 4200);
FORCEADD TAP..6
(-3100 4150);
FORCEPROP 3 LASTPIN (-3050 4150) SIG_NAME M_E_MA<2>
J 0
(-3040 4160);
DISPLAY 0.659574 (-3040 4160);
PAINT MONO (-3040 4160);
DISPLAY INVISIBLE (-3040 4160);
FORCEPROP 1 LASTPIN (-3050 4150) BN 2
J 0
(-3100 4160);
DISPLAY 0.617021 (-3100 4160);
PAINT PINK (-3100 4160);
FORCEPROP 2 LAST CDS_LIB mstr_standard
J 2
(-3100 4150);
DISPLAY 0.787234 (-3100 4150);
PAINT MONO (-3100 4150);
DISPLAY INVISIBLE (-3100 4150);
FORCEPROP 1 LAST BODY_TYPE PLUMBING
J 0
(-3100 4100);
DISPLAY 1.234043 (-3100 4100);
PAINT GREEN (-3100 4100);
DISPLAY INVISIBLE (-3100 4100);
FORCEPROP 1 LAST HDL_TAP TRUE
J 0
(-2775 4025);
DISPLAY 1.234043 (-2775 4025);
PAINT GREEN (-2775 4025);
DISPLAY INVISIBLE (-2775 4025);
FORCEPROP 1 LAST PATH I127
J 0
(-3100 4150);
DISPLAY 0.936170 (-3100 4150);
PAINT GREEN (-3100 4150);
DISPLAY INVISIBLE (-3100 4150);
FORCEADD TAP..6
(-3100 4100);
FORCEPROP 3 LASTPIN (-3050 4100) SIG_NAME M_E_MA<1>
J 0
(-3040 4110);
DISPLAY 0.659574 (-3040 4110);
PAINT MONO (-3040 4110);
DISPLAY INVISIBLE (-3040 4110);
FORCEPROP 1 LASTPIN (-3050 4100) BN 1
J 0
(-3100 4110);
DISPLAY 0.617021 (-3100 4110);
PAINT PINK (-3100 4110);
FORCEPROP 2 LAST CDS_LIB mstr_standard
J 2
(-3100 4100);
DISPLAY 0.787234 (-3100 4100);
PAINT MONO (-3100 4100);
DISPLAY INVISIBLE (-3100 4100);
FORCEPROP 1 LAST BODY_TYPE PLUMBING
J 0
(-3100 4050);
DISPLAY 1.234043 (-3100 4050);
PAINT GREEN (-3100 4050);
DISPLAY INVISIBLE (-3100 4050);
FORCEPROP 1 LAST HDL_TAP TRUE
J 0
(-2775 3975);
DISPLAY 1.234043 (-2775 3975);
PAINT GREEN (-2775 3975);
DISPLAY INVISIBLE (-2775 3975);
FORCEPROP 1 LAST PATH I128
J 0
(-3100 4100);
DISPLAY 0.936170 (-3100 4100);
PAINT GREEN (-3100 4100);
DISPLAY INVISIBLE (-3100 4100);
FORCEADD TAP..6
(-3100 4050);
FORCEPROP 3 LASTPIN (-3050 4050) SIG_NAME M_E_MA<0>
J 0
(-3040 4060);
DISPLAY 0.659574 (-3040 4060);
PAINT MONO (-3040 4060);
DISPLAY INVISIBLE (-3040 4060);
FORCEPROP 1 LASTPIN (-3050 4050) BN 0
J 0
(-3100 4060);
DISPLAY 0.617021 (-3100 4060);
PAINT PINK (-3100 4060);
FORCEPROP 2 LAST CDS_LIB mstr_standard
J 2
(-3100 4050);
DISPLAY 0.787234 (-3100 4050);
PAINT MONO (-3100 4050);
DISPLAY INVISIBLE (-3100 4050);
FORCEPROP 1 LAST BODY_TYPE PLUMBING
J 0
(-3100 4000);
DISPLAY 1.234043 (-3100 4000);
PAINT GREEN (-3100 4000);
DISPLAY INVISIBLE (-3100 4000);
FORCEPROP 1 LAST HDL_TAP TRUE
J 0
(-2775 3925);
DISPLAY 1.234043 (-2775 3925);
PAINT GREEN (-2775 3925);
DISPLAY INVISIBLE (-2775 3925);
FORCEPROP 1 LAST PATH I129
J 0
(-3100 4050);
DISPLAY 0.936170 (-3100 4050);
PAINT GREEN (-3100 4050);
DISPLAY INVISIBLE (-3100 4050);
FORCEADD TAP..6
R 2
(700 4750);
FORCEPROP 3 LASTPIN (650 4750) SIG_NAME M_E_DQS_DP<13>
J 0
(660 4760);
DISPLAY 0.659574 (660 4760);
PAINT MONO (660 4760);
DISPLAY INVISIBLE (660 4760);
FORCEPROP 1 LASTPIN (650 4750) BN 13
J 2
(700 4760);
DISPLAY 0.617021 (700 4760);
PAINT PINK (700 4760);
FORCEPROP 2 LAST CDS_LIB mstr_standard
J 0
(700 4750);
DISPLAY 0.787234 (700 4750);
PAINT MONO (700 4750);
DISPLAY INVISIBLE (700 4750);
FORCEPROP 1 LAST BODY_TYPE PLUMBING
J 2
(700 4700);
DISPLAY 1.234043 (700 4700);
PAINT GREEN (700 4700);
DISPLAY INVISIBLE (700 4700);
FORCEPROP 1 LAST HDL_TAP TRUE
J 2
(375 4625);
DISPLAY 1.234043 (375 4625);
PAINT GREEN (375 4625);
DISPLAY INVISIBLE (375 4625);
FORCEPROP 1 LAST PATH I13
J 2
(700 4750);
DISPLAY 0.936170 (700 4750);
PAINT GREEN (700 4750);
DISPLAY INVISIBLE (700 4750);
FORCEADD TAP..6
(-3100 3950);
FORCEPROP 3 LASTPIN (-3050 3950) SIG_NAME M_E_BA<1>
J 0
(-3040 3960);
DISPLAY 0.659574 (-3040 3960);
PAINT MONO (-3040 3960);
DISPLAY INVISIBLE (-3040 3960);
FORCEPROP 1 LASTPIN (-3050 3950) BN 1
J 0
(-3100 3960);
DISPLAY 0.617021 (-3100 3960);
PAINT PINK (-3100 3960);
FORCEPROP 2 LAST CDS_LIB mstr_standard
J 0
(-3100 3950);
DISPLAY 0.787234 (-3100 3950);
PAINT MONO (-3100 3950);
DISPLAY INVISIBLE (-3100 3950);
FORCEPROP 1 LAST BODY_TYPE PLUMBING
J 0
(-3100 3900);
DISPLAY 1.234043 (-3100 3900);
PAINT GREEN (-3100 3900);
DISPLAY INVISIBLE (-3100 3900);
FORCEPROP 1 LAST HDL_TAP TRUE
J 0
(-2775 3825);
DISPLAY 1.234043 (-2775 3825);
PAINT GREEN (-2775 3825);
DISPLAY INVISIBLE (-2775 3825);
FORCEPROP 1 LAST PATH I130
J 0
(-3100 3950);
DISPLAY 0.936170 (-3100 3950);
PAINT GREEN (-3100 3950);
DISPLAY INVISIBLE (-3100 3950);
FORCEADD OFFPAGE..1
(-3900 4950);
FORCEPROP 2 LAST $XR0 27 
J 0
(-4121 4950);
DISPLAY 0.638298 (-4121 4950);
PAINT MONO (-4121 4950);
FORCEPROP 2 LAST $XR1 52 
J 0
(-4211 4950);
DISPLAY 0.638298 (-4211 4950);
PAINT MONO (-4211 4950);
FORCEPROP 2 LAST CDS_LIB mstr_standard
J 0
(-3900 4950);
DISPLAY 0.787234 (-3900 4950);
PAINT MONO (-3900 4950);
DISPLAY INVISIBLE (-3900 4950);
FORCEPROP 1 LAST OFFPAGE TRUE
J 0
(-3575 4825);
DISPLAY 0.936170 (-3575 4825);
PAINT GREEN (-3575 4825);
DISPLAY INVISIBLE (-3575 4825);
FORCEPROP 1 LAST COMMENT_BODY TRUE
J 0
(-3775 4850);
DISPLAY 0.936170 (-3775 4850);
PAINT GREEN (-3775 4850);
DISPLAY INVISIBLE (-3775 4850);
FORCEPROP 2 LAST PATH I131
J 0
(-3850 5025);
DISPLAY 0.787234 (-3850 5025);
PAINT MONO (-3850 5025);
DISPLAY INVISIBLE (-3850 5025);
FORCEADD OFFPAGE..1
(-3900 4050);
FORCEPROP 2 LAST $XR0 27 
J 0
(-4121 4050);
DISPLAY 0.638298 (-4121 4050);
PAINT MONO (-4121 4050);
FORCEPROP 2 LAST $XR1 52 
J 0
(-4211 4050);
DISPLAY 0.638298 (-4211 4050);
PAINT MONO (-4211 4050);
FORCEPROP 2 LAST CDS_LIB mstr_standard
J 0
(-3900 4050);
DISPLAY 0.787234 (-3900 4050);
PAINT MONO (-3900 4050);
DISPLAY INVISIBLE (-3900 4050);
FORCEPROP 1 LAST OFFPAGE TRUE
J 0
(-3575 3925);
DISPLAY 0.936170 (-3575 3925);
PAINT GREEN (-3575 3925);
DISPLAY INVISIBLE (-3575 3925);
FORCEPROP 1 LAST COMMENT_BODY TRUE
J 0
(-3775 3950);
DISPLAY 0.936170 (-3775 3950);
PAINT GREEN (-3775 3950);
DISPLAY INVISIBLE (-3775 3950);
FORCEPROP 2 LAST PATH I132
J 0
(-3850 4125);
DISPLAY 0.787234 (-3850 4125);
PAINT MONO (-3850 4125);
DISPLAY INVISIBLE (-3850 4125);
FORCEADD TAP..6
(-3100 3900);
FORCEPROP 3 LASTPIN (-3050 3900) SIG_NAME M_E_BA<0>
J 0
(-3040 3910);
DISPLAY 0.659574 (-3040 3910);
PAINT MONO (-3040 3910);
DISPLAY INVISIBLE (-3040 3910);
FORCEPROP 1 LASTPIN (-3050 3900) BN 0
J 0
(-3100 3910);
DISPLAY 0.617021 (-3100 3910);
PAINT PINK (-3100 3910);
FORCEPROP 2 LAST CDS_LIB mstr_standard
J 0
(-3100 3900);
DISPLAY 0.787234 (-3100 3900);
PAINT MONO (-3100 3900);
DISPLAY INVISIBLE (-3100 3900);
FORCEPROP 1 LAST BODY_TYPE PLUMBING
J 0
(-3100 3850);
DISPLAY 1.234043 (-3100 3850);
PAINT GREEN (-3100 3850);
DISPLAY INVISIBLE (-3100 3850);
FORCEPROP 1 LAST HDL_TAP TRUE
J 0
(-2775 3775);
DISPLAY 1.234043 (-2775 3775);
PAINT GREEN (-2775 3775);
DISPLAY INVISIBLE (-2775 3775);
FORCEPROP 1 LAST PATH I133
J 0
(-3100 3900);
DISPLAY 0.936170 (-3100 3900);
PAINT GREEN (-3100 3900);
DISPLAY INVISIBLE (-3100 3900);
FORCEADD TAP..6
(-3100 3850);
FORCEPROP 3 LASTPIN (-3050 3850) SIG_NAME M_E_BG<1>
J 0
(-3040 3860);
DISPLAY 0.659574 (-3040 3860);
PAINT MONO (-3040 3860);
DISPLAY INVISIBLE (-3040 3860);
FORCEPROP 1 LASTPIN (-3050 3850) BN 1
J 0
(-3100 3860);
DISPLAY 0.617021 (-3100 3860);
PAINT PINK (-3100 3860);
FORCEPROP 2 LAST CDS_LIB mstr_standard
J 0
(-3100 3850);
DISPLAY 0.787234 (-3100 3850);
PAINT MONO (-3100 3850);
DISPLAY INVISIBLE (-3100 3850);
FORCEPROP 1 LAST BODY_TYPE PLUMBING
J 0
(-3100 3800);
DISPLAY 1.234043 (-3100 3800);
PAINT GREEN (-3100 3800);
DISPLAY INVISIBLE (-3100 3800);
FORCEPROP 1 LAST HDL_TAP TRUE
J 0
(-2775 3725);
DISPLAY 1.234043 (-2775 3725);
PAINT GREEN (-2775 3725);
DISPLAY INVISIBLE (-2775 3725);
FORCEPROP 1 LAST PATH I134
J 0
(-3100 3850);
DISPLAY 0.936170 (-3100 3850);
PAINT GREEN (-3100 3850);
DISPLAY INVISIBLE (-3100 3850);
FORCEADD TAP..6
(-3100 3800);
FORCEPROP 3 LASTPIN (-3050 3800) SIG_NAME M_E_BG<0>
J 0
(-3040 3810);
DISPLAY 0.659574 (-3040 3810);
PAINT MONO (-3040 3810);
DISPLAY INVISIBLE (-3040 3810);
FORCEPROP 1 LASTPIN (-3050 3800) BN 0
J 0
(-3100 3810);
DISPLAY 0.617021 (-3100 3810);
PAINT PINK (-3100 3810);
FORCEPROP 2 LAST CDS_LIB mstr_standard
J 0
(-3100 3800);
DISPLAY 0.787234 (-3100 3800);
PAINT MONO (-3100 3800);
DISPLAY INVISIBLE (-3100 3800);
FORCEPROP 1 LAST BODY_TYPE PLUMBING
J 0
(-3100 3750);
DISPLAY 1.234043 (-3100 3750);
PAINT GREEN (-3100 3750);
DISPLAY INVISIBLE (-3100 3750);
FORCEPROP 1 LAST HDL_TAP TRUE
J 0
(-2775 3675);
DISPLAY 1.234043 (-2775 3675);
PAINT GREEN (-2775 3675);
DISPLAY INVISIBLE (-2775 3675);
FORCEPROP 1 LAST PATH I135
J 0
(-3100 3800);
DISPLAY 0.936170 (-3100 3800);
PAINT GREEN (-3100 3800);
DISPLAY INVISIBLE (-3100 3800);
FORCEADD OFFPAGE..1
(-3900 3500);
FORCEPROP 2 LAST $XR0 27 
J 0
(-4121 3500);
DISPLAY 0.638298 (-4121 3500);
PAINT MONO (-4121 3500);
FORCEPROP 2 LAST $XR1 52 
J 0
(-4211 3500);
DISPLAY 0.638298 (-4211 3500);
PAINT MONO (-4211 3500);
FORCEPROP 2 LAST CDS_LIB mstr_standard
J 0
(-3900 3500);
DISPLAY 0.787234 (-3900 3500);
PAINT MONO (-3900 3500);
DISPLAY INVISIBLE (-3900 3500);
FORCEPROP 1 LAST OFFPAGE TRUE
J 0
(-3575 3375);
DISPLAY 0.936170 (-3575 3375);
PAINT GREEN (-3575 3375);
DISPLAY INVISIBLE (-3575 3375);
FORCEPROP 1 LAST COMMENT_BODY TRUE
J 0
(-3775 3400);
DISPLAY 0.936170 (-3775 3400);
PAINT GREEN (-3775 3400);
DISPLAY INVISIBLE (-3775 3400);
FORCEPROP 2 LAST PATH I136
J 0
(-3850 3575);
DISPLAY 0.787234 (-3850 3575);
PAINT MONO (-3850 3575);
DISPLAY INVISIBLE (-3850 3575);
FORCEADD OFFPAGE..1
(-3900 3900);
FORCEPROP 2 LAST $XR0 27 
J 0
(-4121 3900);
DISPLAY 0.638298 (-4121 3900);
PAINT MONO (-4121 3900);
FORCEPROP 2 LAST $XR1 52 
J 0
(-4211 3900);
DISPLAY 0.638298 (-4211 3900);
PAINT MONO (-4211 3900);
FORCEPROP 2 LAST CDS_LIB mstr_standard
J 0
(-3900 3900);
DISPLAY 0.787234 (-3900 3900);
PAINT MONO (-3900 3900);
DISPLAY INVISIBLE (-3900 3900);
FORCEPROP 1 LAST OFFPAGE TRUE
J 0
(-3575 3775);
DISPLAY 0.936170 (-3575 3775);
PAINT GREEN (-3575 3775);
DISPLAY INVISIBLE (-3575 3775);
FORCEPROP 1 LAST COMMENT_BODY TRUE
J 0
(-3775 3800);
DISPLAY 0.936170 (-3775 3800);
PAINT GREEN (-3775 3800);
DISPLAY INVISIBLE (-3775 3800);
FORCEPROP 2 LAST PATH I137
J 0
(-3850 3975);
DISPLAY 0.787234 (-3850 3975);
PAINT MONO (-3850 3975);
DISPLAY INVISIBLE (-3850 3975);
FORCEADD TAP..6
(-3100 2800);
FORCEPROP 3 LASTPIN (-3050 2800) SIG_NAME M_E_ECC<7>
J 0
(-3040 2810);
DISPLAY 0.659574 (-3040 2810);
PAINT MONO (-3040 2810);
DISPLAY INVISIBLE (-3040 2810);
FORCEPROP 1 LASTPIN (-3050 2800) BN 7
J 0
(-3100 2810);
DISPLAY 0.617021 (-3100 2810);
PAINT PINK (-3100 2810);
FORCEPROP 2 LAST CDS_LIB mstr_standard
J 0
(-3100 2800);
DISPLAY 0.787234 (-3100 2800);
PAINT MONO (-3100 2800);
DISPLAY INVISIBLE (-3100 2800);
FORCEPROP 1 LAST BODY_TYPE PLUMBING
J 0
(-3100 2750);
DISPLAY 1.234043 (-3100 2750);
PAINT GREEN (-3100 2750);
DISPLAY INVISIBLE (-3100 2750);
FORCEPROP 1 LAST HDL_TAP TRUE
J 0
(-2775 2675);
DISPLAY 1.234043 (-2775 2675);
PAINT GREEN (-2775 2675);
DISPLAY INVISIBLE (-2775 2675);
FORCEPROP 1 LAST PATH I138
J 0
(-3100 2800);
DISPLAY 0.936170 (-3100 2800);
PAINT GREEN (-3100 2800);
DISPLAY INVISIBLE (-3100 2800);
FORCEADD TAP..6
(-3100 2850);
FORCEPROP 3 LASTPIN (-3050 2850) SIG_NAME M_E_ECC<6>
J 0
(-3040 2860);
DISPLAY 0.659574 (-3040 2860);
PAINT MONO (-3040 2860);
DISPLAY INVISIBLE (-3040 2860);
FORCEPROP 1 LASTPIN (-3050 2850) BN 6
J 0
(-3100 2860);
DISPLAY 0.617021 (-3100 2860);
PAINT PINK (-3100 2860);
FORCEPROP 2 LAST CDS_LIB mstr_standard
J 0
(-3100 2850);
DISPLAY 0.787234 (-3100 2850);
PAINT MONO (-3100 2850);
DISPLAY INVISIBLE (-3100 2850);
FORCEPROP 1 LAST BODY_TYPE PLUMBING
J 0
(-3100 2800);
DISPLAY 1.234043 (-3100 2800);
PAINT GREEN (-3100 2800);
DISPLAY INVISIBLE (-3100 2800);
FORCEPROP 1 LAST HDL_TAP TRUE
J 0
(-2775 2725);
DISPLAY 1.234043 (-2775 2725);
PAINT GREEN (-2775 2725);
DISPLAY INVISIBLE (-2775 2725);
FORCEPROP 1 LAST PATH I139
J 0
(-3100 2850);
DISPLAY 0.936170 (-3100 2850);
PAINT GREEN (-3100 2850);
DISPLAY INVISIBLE (-3100 2850);
FORCEADD TAP..6
R 2
(700 4550);
FORCEPROP 3 LASTPIN (650 4550) SIG_NAME M_E_DQS_DP<11>
J 0
(660 4560);
DISPLAY 0.659574 (660 4560);
PAINT MONO (660 4560);
DISPLAY INVISIBLE (660 4560);
FORCEPROP 1 LASTPIN (650 4550) BN 11
J 2
(700 4560);
DISPLAY 0.617021 (700 4560);
PAINT PINK (700 4560);
FORCEPROP 2 LAST CDS_LIB mstr_standard
J 0
(700 4550);
DISPLAY 0.787234 (700 4550);
PAINT MONO (700 4550);
DISPLAY INVISIBLE (700 4550);
FORCEPROP 1 LAST BODY_TYPE PLUMBING
J 2
(700 4500);
DISPLAY 1.234043 (700 4500);
PAINT GREEN (700 4500);
DISPLAY INVISIBLE (700 4500);
FORCEPROP 1 LAST HDL_TAP TRUE
J 2
(375 4425);
DISPLAY 1.234043 (375 4425);
PAINT GREEN (375 4425);
DISPLAY INVISIBLE (375 4425);
FORCEPROP 1 LAST PATH I14
J 2
(700 4550);
DISPLAY 0.936170 (700 4550);
PAINT GREEN (700 4550);
DISPLAY INVISIBLE (700 4550);
FORCEADD TAP..6
(-3100 2750);
FORCEPROP 3 LASTPIN (-3050 2750) SIG_NAME M_E_ECC<4>
J 0
(-3040 2760);
DISPLAY 0.659574 (-3040 2760);
PAINT MONO (-3040 2760);
DISPLAY INVISIBLE (-3040 2760);
FORCEPROP 1 LASTPIN (-3050 2750) BN 4
J 0
(-3100 2760);
DISPLAY 0.617021 (-3100 2760);
PAINT PINK (-3100 2760);
FORCEPROP 2 LAST CDS_LIB mstr_standard
J 0
(-3100 2750);
DISPLAY 0.787234 (-3100 2750);
PAINT MONO (-3100 2750);
DISPLAY INVISIBLE (-3100 2750);
FORCEPROP 1 LAST BODY_TYPE PLUMBING
J 0
(-3100 2700);
DISPLAY 1.234043 (-3100 2700);
PAINT GREEN (-3100 2700);
DISPLAY INVISIBLE (-3100 2700);
FORCEPROP 1 LAST HDL_TAP TRUE
J 0
(-2775 2625);
DISPLAY 1.234043 (-2775 2625);
PAINT GREEN (-2775 2625);
DISPLAY INVISIBLE (-2775 2625);
FORCEPROP 1 LAST PATH I140
J 0
(-3100 2750);
DISPLAY 0.936170 (-3100 2750);
PAINT GREEN (-3100 2750);
DISPLAY INVISIBLE (-3100 2750);
FORCEADD TAP..6
(-3100 2700);
FORCEPROP 3 LASTPIN (-3050 2700) SIG_NAME M_E_ECC<5>
J 0
(-3040 2710);
DISPLAY 0.659574 (-3040 2710);
PAINT MONO (-3040 2710);
DISPLAY INVISIBLE (-3040 2710);
FORCEPROP 1 LASTPIN (-3050 2700) BN 5
J 0
(-3100 2710);
DISPLAY 0.617021 (-3100 2710);
PAINT PINK (-3100 2710);
FORCEPROP 2 LAST CDS_LIB mstr_standard
J 0
(-3100 2700);
DISPLAY 0.787234 (-3100 2700);
PAINT MONO (-3100 2700);
DISPLAY INVISIBLE (-3100 2700);
FORCEPROP 1 LAST BODY_TYPE PLUMBING
J 0
(-3100 2650);
DISPLAY 1.234043 (-3100 2650);
PAINT GREEN (-3100 2650);
DISPLAY INVISIBLE (-3100 2650);
FORCEPROP 1 LAST HDL_TAP TRUE
J 0
(-2775 2575);
DISPLAY 1.234043 (-2775 2575);
PAINT GREEN (-2775 2575);
DISPLAY INVISIBLE (-2775 2575);
FORCEPROP 1 LAST PATH I141
J 0
(-3100 2700);
DISPLAY 0.936170 (-3100 2700);
PAINT GREEN (-3100 2700);
DISPLAY INVISIBLE (-3100 2700);
FORCEADD TAP..6
(-3100 2650);
FORCEPROP 3 LASTPIN (-3050 2650) SIG_NAME M_E_ECC<2>
J 0
(-3040 2660);
DISPLAY 0.659574 (-3040 2660);
PAINT MONO (-3040 2660);
DISPLAY INVISIBLE (-3040 2660);
FORCEPROP 1 LASTPIN (-3050 2650) BN 2
J 0
(-3100 2660);
DISPLAY 0.617021 (-3100 2660);
PAINT PINK (-3100 2660);
FORCEPROP 2 LAST CDS_LIB mstr_standard
J 0
(-3100 2650);
DISPLAY 0.787234 (-3100 2650);
PAINT MONO (-3100 2650);
DISPLAY INVISIBLE (-3100 2650);
FORCEPROP 1 LAST BODY_TYPE PLUMBING
J 0
(-3100 2600);
DISPLAY 1.234043 (-3100 2600);
PAINT GREEN (-3100 2600);
DISPLAY INVISIBLE (-3100 2600);
FORCEPROP 1 LAST HDL_TAP TRUE
J 0
(-2775 2525);
DISPLAY 1.234043 (-2775 2525);
PAINT GREEN (-2775 2525);
DISPLAY INVISIBLE (-2775 2525);
FORCEPROP 1 LAST PATH I142
J 0
(-3100 2650);
DISPLAY 0.936170 (-3100 2650);
PAINT GREEN (-3100 2650);
DISPLAY INVISIBLE (-3100 2650);
FORCEADD TAP..6
(-3100 2600);
FORCEPROP 3 LASTPIN (-3050 2600) SIG_NAME M_E_ECC<3>
J 0
(-3040 2610);
DISPLAY 0.659574 (-3040 2610);
PAINT MONO (-3040 2610);
DISPLAY INVISIBLE (-3040 2610);
FORCEPROP 1 LASTPIN (-3050 2600) BN 3
J 0
(-3100 2610);
DISPLAY 0.617021 (-3100 2610);
PAINT PINK (-3100 2610);
FORCEPROP 2 LAST CDS_LIB mstr_standard
J 0
(-3100 2600);
DISPLAY 0.787234 (-3100 2600);
PAINT MONO (-3100 2600);
DISPLAY INVISIBLE (-3100 2600);
FORCEPROP 1 LAST BODY_TYPE PLUMBING
J 0
(-3100 2550);
DISPLAY 1.234043 (-3100 2550);
PAINT GREEN (-3100 2550);
DISPLAY INVISIBLE (-3100 2550);
FORCEPROP 1 LAST HDL_TAP TRUE
J 0
(-2775 2475);
DISPLAY 1.234043 (-2775 2475);
PAINT GREEN (-2775 2475);
DISPLAY INVISIBLE (-2775 2475);
FORCEPROP 1 LAST PATH I143
J 0
(-3100 2600);
DISPLAY 0.936170 (-3100 2600);
PAINT GREEN (-3100 2600);
DISPLAY INVISIBLE (-3100 2600);
FORCEADD TAP..6
(-3100 2550);
FORCEPROP 3 LASTPIN (-3050 2550) SIG_NAME M_E_ECC<0>
J 0
(-3040 2560);
DISPLAY 0.659574 (-3040 2560);
PAINT MONO (-3040 2560);
DISPLAY INVISIBLE (-3040 2560);
FORCEPROP 1 LASTPIN (-3050 2550) BN 0
J 0
(-3100 2560);
DISPLAY 0.617021 (-3100 2560);
PAINT PINK (-3100 2560);
FORCEPROP 2 LAST CDS_LIB mstr_standard
J 0
(-3100 2550);
DISPLAY 0.787234 (-3100 2550);
PAINT MONO (-3100 2550);
DISPLAY INVISIBLE (-3100 2550);
FORCEPROP 1 LAST BODY_TYPE PLUMBING
J 0
(-3100 2500);
DISPLAY 1.234043 (-3100 2500);
PAINT GREEN (-3100 2500);
DISPLAY INVISIBLE (-3100 2500);
FORCEPROP 1 LAST HDL_TAP TRUE
J 0
(-2775 2425);
DISPLAY 1.234043 (-2775 2425);
PAINT GREEN (-2775 2425);
DISPLAY INVISIBLE (-2775 2425);
FORCEPROP 1 LAST PATH I144
J 0
(-3100 2550);
DISPLAY 0.936170 (-3100 2550);
PAINT GREEN (-3100 2550);
DISPLAY INVISIBLE (-3100 2550);
FORCEADD TAP..6
(-3100 2500);
FORCEPROP 3 LASTPIN (-3050 2500) SIG_NAME M_E_ECC<1>
J 0
(-3040 2510);
DISPLAY 0.659574 (-3040 2510);
PAINT MONO (-3040 2510);
DISPLAY INVISIBLE (-3040 2510);
FORCEPROP 1 LASTPIN (-3050 2500) BN 1
J 0
(-3100 2510);
DISPLAY 0.617021 (-3100 2510);
PAINT PINK (-3100 2510);
FORCEPROP 2 LAST CDS_LIB mstr_standard
J 0
(-3100 2500);
DISPLAY 0.787234 (-3100 2500);
PAINT MONO (-3100 2500);
DISPLAY INVISIBLE (-3100 2500);
FORCEPROP 1 LAST BODY_TYPE PLUMBING
J 0
(-3100 2450);
DISPLAY 1.234043 (-3100 2450);
PAINT GREEN (-3100 2450);
DISPLAY INVISIBLE (-3100 2450);
FORCEPROP 1 LAST HDL_TAP TRUE
J 0
(-2775 2375);
DISPLAY 1.234043 (-2775 2375);
PAINT GREEN (-2775 2375);
DISPLAY INVISIBLE (-2775 2375);
FORCEPROP 1 LAST PATH I145
J 0
(-3100 2500);
DISPLAY 0.936170 (-3100 2500);
PAINT GREEN (-3100 2500);
DISPLAY INVISIBLE (-3100 2500);
FORCEADD OFFPAGE..1
(-3900 2850);
FORCEPROP 2 LAST $XR0 27 
J 0
(-4181 2850);
DISPLAY 0.638298 (-4181 2850);
PAINT MONO (-4181 2850);
FORCEPROP 2 LAST $XR1 52 
J 0
(-4271 2850);
DISPLAY 0.638298 (-4271 2850);
PAINT MONO (-4271 2850);
FORCEPROP 2 LAST CDS_LIB mstr_standard
J 0
(-3900 2850);
DISPLAY 0.787234 (-3900 2850);
PAINT MONO (-3900 2850);
DISPLAY INVISIBLE (-3900 2850);
FORCEPROP 1 LAST OFFPAGE TRUE
J 0
(-3575 2725);
DISPLAY 0.936170 (-3575 2725);
PAINT GREEN (-3575 2725);
DISPLAY INVISIBLE (-3575 2725);
FORCEPROP 1 LAST COMMENT_BODY TRUE
J 0
(-3775 2750);
DISPLAY 0.936170 (-3775 2750);
PAINT GREEN (-3775 2750);
DISPLAY INVISIBLE (-3775 2750);
FORCEPROP 2 LAST PATH I146
J 0
(-3850 2925);
DISPLAY 0.787234 (-3850 2925);
PAINT MONO (-3850 2925);
DISPLAY INVISIBLE (-3850 2925);
FORCEADD OFFPAGE..1
(-3900 2200);
FORCEPROP 2 LAST $XR0 27 
J 0
(-4181 2200);
DISPLAY 0.638298 (-4181 2200);
PAINT MONO (-4181 2200);
FORCEPROP 2 LAST $XR1 52 
J 0
(-4271 2200);
DISPLAY 0.638298 (-4271 2200);
PAINT MONO (-4271 2200);
FORCEPROP 2 LAST CDS_LIB mstr_standard
J 0
(-3900 2200);
DISPLAY 0.787234 (-3900 2200);
PAINT MONO (-3900 2200);
DISPLAY INVISIBLE (-3900 2200);
FORCEPROP 1 LAST OFFPAGE TRUE
J 0
(-3575 2075);
DISPLAY 0.936170 (-3575 2075);
PAINT GREEN (-3575 2075);
DISPLAY INVISIBLE (-3575 2075);
FORCEPROP 1 LAST COMMENT_BODY TRUE
J 0
(-3775 2100);
DISPLAY 0.936170 (-3775 2100);
PAINT GREEN (-3775 2100);
DISPLAY INVISIBLE (-3775 2100);
FORCEPROP 2 LAST PATH I147
J 0
(-3850 2275);
DISPLAY 0.787234 (-3850 2275);
PAINT MONO (-3850 2275);
DISPLAY INVISIBLE (-3850 2275);
FORCEADD OFFPAGE..5
(-3925 2250);
FORCEPROP 2 LAST $XR0 52 
J 0
(-4179 2250);
DISPLAY 0.638298 (-4179 2250);
PAINT MONO (-4179 2250);
FORCEPROP 2 LAST $XR1 27 
J 0
(-4269 2250);
DISPLAY 0.638298 (-4269 2250);
PAINT MONO (-4269 2250);
FORCEPROP 2 LAST CDS_LIB mstr_standard
J 0
(-3925 2250);
DISPLAY 0.787234 (-3925 2250);
PAINT MONO (-3925 2250);
DISPLAY INVISIBLE (-3925 2250);
FORCEPROP 1 LAST OFFPAGE TRUE
J 0
(-3600 2125);
DISPLAY 1.404255 (-3600 2125);
PAINT GREEN (-3600 2125);
DISPLAY INVISIBLE (-3600 2125);
FORCEPROP 1 LAST COMMENT_BODY TRUE
J 0
(-3825 2175);
DISPLAY 1.404255 (-3825 2175);
PAINT GREEN (-3825 2175);
DISPLAY INVISIBLE (-3825 2175);
FORCEPROP 2 LAST PATH I148
J 0
(-3875 2325);
DISPLAY 0.787234 (-3875 2325);
PAINT MONO (-3875 2325);
DISPLAY INVISIBLE (-3875 2325);
FORCEADD OFFPAGE..1
(-3900 2800);
FORCEPROP 2 LAST $XR0 21 
J 0
(-4121 2800);
DISPLAY 0.638298 (-4121 2800);
PAINT MONO (-4121 2800);
FORCEPROP 2 LAST $XR1 49 
J 0
(-4211 2800);
DISPLAY 0.638298 (-4211 2800);
PAINT MONO (-4211 2800);
FORCEPROP 2 LAST $XR2 50 
J 0
(-4301 2800);
DISPLAY 0.638298 (-4301 2800);
PAINT MONO (-4301 2800);
FORCEPROP 2 LAST $XR3 52 
J 0
(-4391 2800);
DISPLAY 0.638298 (-4391 2800);
PAINT MONO (-4391 2800);
FORCEPROP 2 LAST $XR4 53 
J 0
(-4481 2800);
DISPLAY 0.638298 (-4481 2800);
PAINT MONO (-4481 2800);
FORCEPROP 2 LAST $XR5 54 
J 0
(-4571 2800);
DISPLAY 0.638298 (-4571 2800);
PAINT MONO (-4571 2800);
FORCEPROP 2 LAST CDS_LIB mstr_standard
J 0
(-3900 2800);
DISPLAY 0.787234 (-3900 2800);
PAINT MONO (-3900 2800);
DISPLAY INVISIBLE (-3900 2800);
FORCEPROP 1 LAST OFFPAGE TRUE
J 0
(-3575 2675);
DISPLAY 0.936170 (-3575 2675);
PAINT GREEN (-3575 2675);
DISPLAY INVISIBLE (-3575 2675);
FORCEPROP 1 LAST COMMENT_BODY TRUE
J 0
(-3775 2700);
DISPLAY 0.936170 (-3775 2700);
PAINT GREEN (-3775 2700);
DISPLAY INVISIBLE (-3775 2700);
FORCEPROP 2 LAST PATH I149
J 0
(-3850 2875);
DISPLAY 0.787234 (-3850 2875);
PAINT MONO (-3850 2875);
DISPLAY INVISIBLE (-3850 2875);
FORCEADD TAP..6
R 2
(700 4650);
FORCEPROP 3 LASTPIN (650 4650) SIG_NAME M_E_DQS_DP<12>
J 0
(660 4660);
DISPLAY 0.659574 (660 4660);
PAINT MONO (660 4660);
DISPLAY INVISIBLE (660 4660);
FORCEPROP 1 LASTPIN (650 4650) BN 12
J 2
(700 4660);
DISPLAY 0.617021 (700 4660);
PAINT PINK (700 4660);
FORCEPROP 2 LAST CDS_LIB mstr_standard
J 0
(700 4650);
DISPLAY 0.787234 (700 4650);
PAINT MONO (700 4650);
DISPLAY INVISIBLE (700 4650);
FORCEPROP 1 LAST BODY_TYPE PLUMBING
J 2
(700 4600);
DISPLAY 1.234043 (700 4600);
PAINT GREEN (700 4600);
DISPLAY INVISIBLE (700 4600);
FORCEPROP 1 LAST HDL_TAP TRUE
J 2
(375 4525);
DISPLAY 1.234043 (375 4525);
PAINT GREEN (375 4525);
DISPLAY INVISIBLE (375 4525);
FORCEPROP 1 LAST PATH I15
J 2
(700 4650);
DISPLAY 0.936170 (700 4650);
PAINT GREEN (700 4650);
DISPLAY INVISIBLE (700 4650);
FORCEADD OFFPAGE..6
(-3900 2900);
FORCEPROP 2 LAST $XR0 27 
J 0
(-4179 2900);
DISPLAY 0.638298 (-4179 2900);
PAINT MONO (-4179 2900);
FORCEPROP 2 LAST $XR1 52 
J 0
(-4269 2900);
DISPLAY 0.638298 (-4269 2900);
PAINT MONO (-4269 2900);
FORCEPROP 2 LAST CDS_LIB mstr_standard
J 0
(-3900 2900);
DISPLAY 0.787234 (-3900 2900);
PAINT MONO (-3900 2900);
DISPLAY INVISIBLE (-3900 2900);
FORCEPROP 1 LAST OFFPAGE TRUE
J 0
(-3575 2775);
DISPLAY 0.936170 (-3575 2775);
PAINT GREEN (-3575 2775);
DISPLAY INVISIBLE (-3575 2775);
FORCEPROP 1 LAST COMMENT_BODY TRUE
J 0
(-3800 2825);
DISPLAY 0.936170 (-3800 2825);
PAINT GREEN (-3800 2825);
DISPLAY INVISIBLE (-3800 2825);
FORCEPROP 2 LAST PATH I150
J 0
(-3850 2975);
DISPLAY 0.787234 (-3850 2975);
PAINT MONO (-3850 2975);
DISPLAY INVISIBLE (-3850 2975);
FORCEADD OFFPAGE..1
(-4800 1750);
FORCEPROP 2 LAST $XR0 98 
J 0
(-5051 1750);
DISPLAY 0.638298 (-5051 1750);
PAINT MONO (-5051 1750);
FORCEPROP 2 LAST $XR1 52 
J 0
(-5141 1750);
DISPLAY 0.638298 (-5141 1750);
PAINT MONO (-5141 1750);
FORCEPROP 2 LAST CDS_LIB mstr_standard
J 0
(-4800 1750);
DISPLAY 0.787234 (-4800 1750);
PAINT MONO (-4800 1750);
DISPLAY INVISIBLE (-4800 1750);
FORCEPROP 1 LAST OFFPAGE TRUE
J 0
(-4475 1625);
DISPLAY 0.936170 (-4475 1625);
PAINT GREEN (-4475 1625);
DISPLAY INVISIBLE (-4475 1625);
FORCEPROP 1 LAST COMMENT_BODY TRUE
J 0
(-4675 1650);
DISPLAY 0.936170 (-4675 1650);
PAINT GREEN (-4675 1650);
DISPLAY INVISIBLE (-4675 1650);
FORCEPROP 2 LAST PATH I151
J 0
(-4750 1825);
DISPLAY 0.787234 (-4750 1825);
PAINT MONO (-4750 1825);
DISPLAY INVISIBLE (-4750 1825);
FORCEADD TAP..6
(-3500 3600);
FORCEPROP 3 LASTPIN (-3450 3600) SIG_NAME M_E_CLK_DP<0>
J 0
(-3440 3610);
DISPLAY 0.659574 (-3440 3610);
PAINT MONO (-3440 3610);
DISPLAY INVISIBLE (-3440 3610);
FORCEPROP 1 LASTPIN (-3450 3600) BN 0
J 0
(-3500 3610);
DISPLAY 0.617021 (-3500 3610);
PAINT PINK (-3500 3610);
FORCEPROP 2 LAST CDS_LIB mstr_standard
J 0
(-3500 3600);
DISPLAY 0.787234 (-3500 3600);
PAINT MONO (-3500 3600);
DISPLAY INVISIBLE (-3500 3600);
FORCEPROP 1 LAST BODY_TYPE PLUMBING
J 0
(-3500 3550);
DISPLAY 1.234043 (-3500 3550);
PAINT GREEN (-3500 3550);
DISPLAY INVISIBLE (-3500 3550);
FORCEPROP 1 LAST HDL_TAP TRUE
J 0
(-3175 3475);
DISPLAY 1.234043 (-3175 3475);
PAINT GREEN (-3175 3475);
DISPLAY INVISIBLE (-3175 3475);
FORCEPROP 1 LAST PATH I152
J 0
(-3500 3600);
DISPLAY 0.936170 (-3500 3600);
PAINT GREEN (-3500 3600);
DISPLAY INVISIBLE (-3500 3600);
FORCEADD TAP..6
(-3650 3550);
FORCEPROP 3 LASTPIN (-3600 3550) SIG_NAME M_E_CLK_DN<0>
J 0
(-3590 3560);
DISPLAY 0.659574 (-3590 3560);
PAINT MONO (-3590 3560);
DISPLAY INVISIBLE (-3590 3560);
FORCEPROP 1 LASTPIN (-3600 3550) BN 0
J 0
(-3650 3560);
DISPLAY 0.617021 (-3650 3560);
PAINT PINK (-3650 3560);
FORCEPROP 2 LAST CDS_LIB mstr_standard
J 0
(-3650 3550);
DISPLAY 0.787234 (-3650 3550);
PAINT MONO (-3650 3550);
DISPLAY INVISIBLE (-3650 3550);
FORCEPROP 1 LAST BODY_TYPE PLUMBING
J 0
(-3650 3500);
DISPLAY 1.234043 (-3650 3500);
PAINT GREEN (-3650 3500);
DISPLAY INVISIBLE (-3650 3500);
FORCEPROP 1 LAST HDL_TAP TRUE
J 0
(-3325 3425);
DISPLAY 1.234043 (-3325 3425);
PAINT GREEN (-3325 3425);
DISPLAY INVISIBLE (-3325 3425);
FORCEPROP 1 LAST PATH I153
J 0
(-3650 3550);
DISPLAY 0.936170 (-3650 3550);
PAINT GREEN (-3650 3550);
DISPLAY INVISIBLE (-3650 3550);
FORCEADD OFFPAGE..1
(-4200 3750);
FORCEPROP 2 LAST $XR0 27 
J 0
(-4451 3750);
DISPLAY 0.638298 (-4451 3750);
PAINT MONO (-4451 3750);
FORCEPROP 2 LAST $XR1 52 
J 0
(-4541 3750);
DISPLAY 0.638298 (-4541 3750);
PAINT MONO (-4541 3750);
FORCEPROP 2 LAST CDS_LIB mstr_standard
J 0
(-4200 3750);
DISPLAY 0.787234 (-4200 3750);
PAINT MONO (-4200 3750);
DISPLAY INVISIBLE (-4200 3750);
FORCEPROP 1 LAST OFFPAGE TRUE
J 0
(-3875 3625);
DISPLAY 0.936170 (-3875 3625);
PAINT GREEN (-3875 3625);
DISPLAY INVISIBLE (-3875 3625);
FORCEPROP 1 LAST COMMENT_BODY TRUE
J 0
(-4075 3650);
DISPLAY 0.936170 (-4075 3650);
PAINT GREEN (-4075 3650);
DISPLAY INVISIBLE (-4075 3650);
FORCEPROP 2 LAST PATH I154
J 0
(-4150 3825);
DISPLAY 0.787234 (-4150 3825);
PAINT MONO (-4150 3825);
DISPLAY INVISIBLE (-4150 3825);
FORCEADD OFFPAGE..1
(-4200 3800);
FORCEPROP 2 LAST $XR0 27 
J 0
(-4451 3800);
DISPLAY 0.638298 (-4451 3800);
PAINT MONO (-4451 3800);
FORCEPROP 2 LAST $XR1 52 
J 0
(-4541 3800);
DISPLAY 0.638298 (-4541 3800);
PAINT MONO (-4541 3800);
FORCEPROP 2 LAST CDS_LIB mstr_standard
J 0
(-4200 3800);
DISPLAY 0.787234 (-4200 3800);
PAINT MONO (-4200 3800);
DISPLAY INVISIBLE (-4200 3800);
FORCEPROP 1 LAST OFFPAGE TRUE
J 0
(-3875 3675);
DISPLAY 0.936170 (-3875 3675);
PAINT GREEN (-3875 3675);
DISPLAY INVISIBLE (-3875 3675);
FORCEPROP 1 LAST COMMENT_BODY TRUE
J 0
(-4075 3700);
DISPLAY 0.936170 (-4075 3700);
PAINT GREEN (-4075 3700);
DISPLAY INVISIBLE (-4075 3700);
FORCEPROP 2 LAST PATH I155
J 0
(-4150 3875);
DISPLAY 0.787234 (-4150 3875);
PAINT MONO (-4150 3875);
DISPLAY INVISIBLE (-4150 3875);
FORCEADD TAP..6
(-3100 3400);
FORCEPROP 3 LASTPIN (-3050 3400) SIG_NAME M_E_CS_N<3>
J 0
(-3040 3410);
DISPLAY 0.659574 (-3040 3410);
PAINT MONO (-3040 3410);
DISPLAY INVISIBLE (-3040 3410);
FORCEPROP 1 LASTPIN (-3050 3400) BN 3
J 0
(-3100 3410);
DISPLAY 0.617021 (-3100 3410);
PAINT PINK (-3100 3410);
FORCEPROP 2 LAST CDS_LIB mstr_standard
J 0
(-3100 3400);
DISPLAY 0.787234 (-3100 3400);
PAINT MONO (-3100 3400);
DISPLAY INVISIBLE (-3100 3400);
FORCEPROP 1 LAST BODY_TYPE PLUMBING
J 0
(-3100 3350);
DISPLAY 1.234043 (-3100 3350);
PAINT GREEN (-3100 3350);
DISPLAY INVISIBLE (-3100 3350);
FORCEPROP 1 LAST HDL_TAP TRUE
J 0
(-2775 3275);
DISPLAY 1.234043 (-2775 3275);
PAINT GREEN (-2775 3275);
DISPLAY INVISIBLE (-2775 3275);
FORCEPROP 1 LAST PATH I156
J 0
(-3100 3400);
DISPLAY 0.936170 (-3100 3400);
PAINT GREEN (-3100 3400);
DISPLAY INVISIBLE (-3100 3400);
FORCEADD TAP..6
(-3100 3350);
FORCEPROP 3 LASTPIN (-3050 3350) SIG_NAME M_E_CS_N<2>
J 0
(-3040 3360);
DISPLAY 0.659574 (-3040 3360);
PAINT MONO (-3040 3360);
DISPLAY INVISIBLE (-3040 3360);
FORCEPROP 1 LASTPIN (-3050 3350) BN 2
J 0
(-3100 3360);
DISPLAY 0.617021 (-3100 3360);
PAINT PINK (-3100 3360);
FORCEPROP 2 LAST CDS_LIB mstr_standard
J 0
(-3100 3350);
DISPLAY 0.787234 (-3100 3350);
PAINT MONO (-3100 3350);
DISPLAY INVISIBLE (-3100 3350);
FORCEPROP 1 LAST BODY_TYPE PLUMBING
J 0
(-3100 3300);
DISPLAY 1.234043 (-3100 3300);
PAINT GREEN (-3100 3300);
DISPLAY INVISIBLE (-3100 3300);
FORCEPROP 1 LAST HDL_TAP TRUE
J 0
(-2775 3225);
DISPLAY 1.234043 (-2775 3225);
PAINT GREEN (-2775 3225);
DISPLAY INVISIBLE (-2775 3225);
FORCEPROP 1 LAST PATH I157
J 0
(-3100 3350);
DISPLAY 0.936170 (-3100 3350);
PAINT GREEN (-3100 3350);
DISPLAY INVISIBLE (-3100 3350);
FORCEADD TAP..6
(-3100 3300);
FORCEPROP 3 LASTPIN (-3050 3300) SIG_NAME M_E_CS_N<1>
J 0
(-3040 3310);
DISPLAY 0.659574 (-3040 3310);
PAINT MONO (-3040 3310);
DISPLAY INVISIBLE (-3040 3310);
FORCEPROP 1 LASTPIN (-3050 3300) BN 1
J 0
(-3100 3310);
DISPLAY 0.617021 (-3100 3310);
PAINT PINK (-3100 3310);
FORCEPROP 2 LAST CDS_LIB mstr_standard
J 0
(-3100 3300);
DISPLAY 0.787234 (-3100 3300);
PAINT MONO (-3100 3300);
DISPLAY INVISIBLE (-3100 3300);
FORCEPROP 1 LAST BODY_TYPE PLUMBING
J 0
(-3100 3250);
DISPLAY 1.234043 (-3100 3250);
PAINT GREEN (-3100 3250);
DISPLAY INVISIBLE (-3100 3250);
FORCEPROP 1 LAST HDL_TAP TRUE
J 0
(-2775 3175);
DISPLAY 1.234043 (-2775 3175);
PAINT GREEN (-2775 3175);
DISPLAY INVISIBLE (-2775 3175);
FORCEPROP 1 LAST PATH I158
J 0
(-3100 3300);
DISPLAY 0.936170 (-3100 3300);
PAINT GREEN (-3100 3300);
DISPLAY INVISIBLE (-3100 3300);
FORCEADD TAP..6
(-3100 3250);
FORCEPROP 3 LASTPIN (-3050 3250) SIG_NAME M_E_CS_N<0>
J 0
(-3040 3260);
DISPLAY 0.659574 (-3040 3260);
PAINT MONO (-3040 3260);
DISPLAY INVISIBLE (-3040 3260);
FORCEPROP 1 LASTPIN (-3050 3250) BN 0
J 0
(-3100 3260);
DISPLAY 0.617021 (-3100 3260);
PAINT PINK (-3100 3260);
FORCEPROP 2 LAST CDS_LIB mstr_standard
J 0
(-3100 3250);
DISPLAY 0.787234 (-3100 3250);
PAINT MONO (-3100 3250);
DISPLAY INVISIBLE (-3100 3250);
FORCEPROP 1 LAST BODY_TYPE PLUMBING
J 0
(-3100 3200);
DISPLAY 1.234043 (-3100 3200);
PAINT GREEN (-3100 3200);
DISPLAY INVISIBLE (-3100 3200);
FORCEPROP 1 LAST HDL_TAP TRUE
J 0
(-2775 3125);
DISPLAY 1.234043 (-2775 3125);
PAINT GREEN (-2775 3125);
DISPLAY INVISIBLE (-2775 3125);
FORCEPROP 1 LAST PATH I159
J 0
(-3100 3250);
DISPLAY 0.936170 (-3100 3250);
PAINT GREEN (-3100 3250);
DISPLAY INVISIBLE (-3100 3250);
FORCEADD PVDDQ_DEF..1
(-1225 2600);
FORCEPROP 3 LASTPIN (-1225 2550) SIG_NAME PVDDQ_DEF\g
J 0
(-1215 2560);
DISPLAY 0.659574 (-1215 2560);
PAINT MONO (-1215 2560);
DISPLAY INVISIBLE (-1215 2560);
FORCEPROP 1 LAST VOLTAGE 1.2V
J 0
(-1270 2557);
DISPLAY 0.340426 (-1270 2557);
PAINT SKYBLUE (-1270 2557);
DISPLAY INVISIBLE (-1270 2557);
FORCEPROP 2 LAST BOM_COST MEM
J 0
(-1225 2605);
PAINT ORANGE (-1225 2605);
DISPLAY INVISIBLE (-1225 2605);
FORCEPROP 2 LAST CDS_LIB mstr_symbols
J 0
(-1225 2600);
PAINT ORANGE (-1225 2600);
DISPLAY INVISIBLE (-1225 2600);
FORCEPROP 1 LAST BODY_TYPE PLUMBING
J 0
(-1270 2557);
DISPLAY 0.340426 (-1270 2557);
PAINT GREEN (-1270 2557);
DISPLAY INVISIBLE (-1270 2557);
FORCEPROP 1 LAST PATH I16
J 0
(-1175 2625);
DISPLAY 0.872340 (-1175 2625);
PAINT AQUA (-1175 2625);
DISPLAY INVISIBLE (-1175 2625);
FORCEPROP 2 LAST ROOM DDR4_CH_B
J 0
(-1225 2700);
DISPLAY 0.787234 (-1225 2700);
PAINT ORANGE (-1225 2700);
DISPLAY INVISIBLE (-1225 2700);
FORCEPROP 1 LAST HDL_POWER PVDDQ_DEF
J 1
(-1225 2650);
DISPLAY 0.872340 (-1225 2650);
PAINT GREEN (-1225 2650);
DISPLAY INVISIBLE (-1225 2650);
FORCEADD TAP..6
(-3150 3150);
FORCEPROP 3 LASTPIN (-3100 3150) SIG_NAME M_E_CKE<1>
J 0
(-3090 3160);
DISPLAY 0.659574 (-3090 3160);
PAINT MONO (-3090 3160);
DISPLAY INVISIBLE (-3090 3160);
FORCEPROP 1 LASTPIN (-3100 3150) BN 1
J 0
(-3150 3160);
DISPLAY 0.617021 (-3150 3160);
PAINT PINK (-3150 3160);
FORCEPROP 2 LAST CDS_LIB mstr_standard
J 0
(-3150 3150);
DISPLAY 0.787234 (-3150 3150);
PAINT MONO (-3150 3150);
DISPLAY INVISIBLE (-3150 3150);
FORCEPROP 1 LAST BODY_TYPE PLUMBING
J 0
(-3150 3100);
DISPLAY 1.234043 (-3150 3100);
PAINT GREEN (-3150 3100);
DISPLAY INVISIBLE (-3150 3100);
FORCEPROP 1 LAST HDL_TAP TRUE
J 0
(-2825 3025);
DISPLAY 1.234043 (-2825 3025);
PAINT GREEN (-2825 3025);
DISPLAY INVISIBLE (-2825 3025);
FORCEPROP 1 LAST PATH I160
J 0
(-3150 3150);
DISPLAY 0.936170 (-3150 3150);
PAINT GREEN (-3150 3150);
DISPLAY INVISIBLE (-3150 3150);
FORCEADD OFFPAGE..1
(-3900 3450);
FORCEPROP 2 LAST $XR0 27 
J 0
(-4121 3450);
DISPLAY 0.638298 (-4121 3450);
PAINT MONO (-4121 3450);
FORCEPROP 2 LAST $XR1 52 
J 0
(-4211 3450);
DISPLAY 0.638298 (-4211 3450);
PAINT MONO (-4211 3450);
FORCEPROP 2 LAST CDS_LIB mstr_standard
J 0
(-3900 3450);
DISPLAY 0.787234 (-3900 3450);
PAINT MONO (-3900 3450);
DISPLAY INVISIBLE (-3900 3450);
FORCEPROP 1 LAST OFFPAGE TRUE
J 0
(-3575 3325);
DISPLAY 0.936170 (-3575 3325);
PAINT GREEN (-3575 3325);
DISPLAY INVISIBLE (-3575 3325);
FORCEPROP 1 LAST COMMENT_BODY TRUE
J 0
(-3775 3350);
DISPLAY 0.936170 (-3775 3350);
PAINT GREEN (-3775 3350);
DISPLAY INVISIBLE (-3775 3350);
FORCEPROP 2 LAST PATH I161
J 0
(-3850 3525);
DISPLAY 0.787234 (-3850 3525);
PAINT MONO (-3850 3525);
DISPLAY INVISIBLE (-3850 3525);
FORCEADD OFFPAGE..1
(-3900 3200);
FORCEPROP 2 LAST $XR0 27 
J 0
(-4121 3200);
DISPLAY 0.638298 (-4121 3200);
PAINT MONO (-4121 3200);
FORCEPROP 2 LAST $XR1 52 
J 0
(-4211 3200);
DISPLAY 0.638298 (-4211 3200);
PAINT MONO (-4211 3200);
FORCEPROP 2 LAST CDS_LIB mstr_standard
J 0
(-3900 3200);
DISPLAY 0.787234 (-3900 3200);
PAINT MONO (-3900 3200);
DISPLAY INVISIBLE (-3900 3200);
FORCEPROP 1 LAST OFFPAGE TRUE
J 0
(-3575 3075);
DISPLAY 0.936170 (-3575 3075);
PAINT GREEN (-3575 3075);
DISPLAY INVISIBLE (-3575 3075);
FORCEPROP 1 LAST COMMENT_BODY TRUE
J 0
(-3775 3100);
DISPLAY 0.936170 (-3775 3100);
PAINT GREEN (-3775 3100);
DISPLAY INVISIBLE (-3775 3100);
FORCEPROP 2 LAST PATH I162
J 0
(-3850 3275);
DISPLAY 0.787234 (-3850 3275);
PAINT MONO (-3850 3275);
DISPLAY INVISIBLE (-3850 3275);
FORCEADD TAP..6
(-3150 3100);
FORCEPROP 3 LASTPIN (-3100 3100) SIG_NAME M_E_CKE<0>
J 0
(-3090 3110);
DISPLAY 0.659574 (-3090 3110);
PAINT MONO (-3090 3110);
DISPLAY INVISIBLE (-3090 3110);
FORCEPROP 1 LASTPIN (-3100 3100) BN 0
J 0
(-3150 3110);
DISPLAY 0.617021 (-3150 3110);
PAINT PINK (-3150 3110);
FORCEPROP 2 LAST CDS_LIB mstr_standard
J 0
(-3150 3100);
DISPLAY 0.787234 (-3150 3100);
PAINT MONO (-3150 3100);
DISPLAY INVISIBLE (-3150 3100);
FORCEPROP 1 LAST BODY_TYPE PLUMBING
J 0
(-3150 3050);
DISPLAY 1.234043 (-3150 3050);
PAINT GREEN (-3150 3050);
DISPLAY INVISIBLE (-3150 3050);
FORCEPROP 1 LAST HDL_TAP TRUE
J 0
(-2825 2975);
DISPLAY 1.234043 (-2825 2975);
PAINT GREEN (-2825 2975);
DISPLAY INVISIBLE (-2825 2975);
FORCEPROP 1 LAST PATH I163
J 0
(-3150 3100);
DISPLAY 0.936170 (-3150 3100);
PAINT GREEN (-3150 3100);
DISPLAY INVISIBLE (-3150 3100);
FORCEADD TAP..6
(-3100 3000);
FORCEPROP 3 LASTPIN (-3050 3000) SIG_NAME M_E_ODT<1>
J 0
(-3040 3010);
DISPLAY 0.659574 (-3040 3010);
PAINT MONO (-3040 3010);
DISPLAY INVISIBLE (-3040 3010);
FORCEPROP 1 LASTPIN (-3050 3000) BN 1
J 0
(-3100 3010);
DISPLAY 0.617021 (-3100 3010);
PAINT PINK (-3100 3010);
FORCEPROP 2 LAST CDS_LIB mstr_standard
J 0
(-3100 3000);
DISPLAY 0.787234 (-3100 3000);
PAINT MONO (-3100 3000);
DISPLAY INVISIBLE (-3100 3000);
FORCEPROP 1 LAST BODY_TYPE PLUMBING
J 0
(-3100 2950);
DISPLAY 1.234043 (-3100 2950);
PAINT GREEN (-3100 2950);
DISPLAY INVISIBLE (-3100 2950);
FORCEPROP 1 LAST HDL_TAP TRUE
J 0
(-2775 2875);
DISPLAY 1.234043 (-2775 2875);
PAINT GREEN (-2775 2875);
DISPLAY INVISIBLE (-2775 2875);
FORCEPROP 1 LAST PATH I164
J 0
(-3100 3000);
DISPLAY 0.936170 (-3100 3000);
PAINT GREEN (-3100 3000);
DISPLAY INVISIBLE (-3100 3000);
FORCEADD OFFPAGE..1
(-3900 3050);
FORCEPROP 2 LAST $XR0 27 
J 0
(-4121 3050);
DISPLAY 0.638298 (-4121 3050);
PAINT MONO (-4121 3050);
FORCEPROP 2 LAST $XR1 52 
J 0
(-4211 3050);
DISPLAY 0.638298 (-4211 3050);
PAINT MONO (-4211 3050);
FORCEPROP 2 LAST CDS_LIB mstr_standard
J 0
(-3900 3050);
DISPLAY 0.787234 (-3900 3050);
PAINT MONO (-3900 3050);
DISPLAY INVISIBLE (-3900 3050);
FORCEPROP 1 LAST OFFPAGE TRUE
J 0
(-3575 2925);
DISPLAY 0.936170 (-3575 2925);
PAINT GREEN (-3575 2925);
DISPLAY INVISIBLE (-3575 2925);
FORCEPROP 1 LAST COMMENT_BODY TRUE
J 0
(-3775 2950);
DISPLAY 0.936170 (-3775 2950);
PAINT GREEN (-3775 2950);
DISPLAY INVISIBLE (-3775 2950);
FORCEPROP 2 LAST PATH I165
J 0
(-3850 3125);
DISPLAY 0.787234 (-3850 3125);
PAINT MONO (-3850 3125);
DISPLAY INVISIBLE (-3850 3125);
FORCEADD TAP..6
(-3100 2950);
FORCEPROP 3 LASTPIN (-3050 2950) SIG_NAME M_E_ODT<0>
J 0
(-3040 2960);
DISPLAY 0.659574 (-3040 2960);
PAINT MONO (-3040 2960);
DISPLAY INVISIBLE (-3040 2960);
FORCEPROP 1 LASTPIN (-3050 2950) BN 0
J 0
(-3100 2960);
DISPLAY 0.617021 (-3100 2960);
PAINT PINK (-3100 2960);
FORCEPROP 2 LAST CDS_LIB mstr_standard
J 0
(-3100 2950);
DISPLAY 0.787234 (-3100 2950);
PAINT MONO (-3100 2950);
DISPLAY INVISIBLE (-3100 2950);
FORCEPROP 1 LAST BODY_TYPE PLUMBING
J 0
(-3100 2900);
DISPLAY 1.234043 (-3100 2900);
PAINT GREEN (-3100 2900);
DISPLAY INVISIBLE (-3100 2900);
FORCEPROP 1 LAST HDL_TAP TRUE
J 0
(-2775 2825);
DISPLAY 1.234043 (-2775 2825);
PAINT GREEN (-2775 2825);
DISPLAY INVISIBLE (-2775 2825);
FORCEPROP 1 LAST PATH I166
J 0
(-3100 2950);
DISPLAY 0.936170 (-3100 2950);
PAINT GREEN (-3100 2950);
DISPLAY INVISIBLE (-3100 2950);
FORCEADD SCONN288_H44441004..4
(-150 2050);
FORCEPROP 1 LAST LOCATION J4A2
J 0
(-600 3150);
DISPLAY 0.617021 (-600 3150);
PAINT AQUA (-600 3150);
FORCEPROP 1 LAST PART_NUMBER H44441-004
J 0
(-600 1000);
DISPLAY 0.617021 (-600 1000);
PAINT BLUE (-600 1000);
FORCEPROP 1 LAST MATERIAL SCONN
J 0
(-600 3100);
DISPLAY 0.617021 (-600 3100);
PAINT SKYBLUE (-600 3100);
FORCEPROP 2 LASTPIN (-650 2600) $PN 77
J 2
(-660 2610);
DISPLAY 0.617021 (-660 2610);
PAINT ORANGE (-660 2610);
FORCEPROP 2 LASTPIN (-650 2550) $PN 221
J 2
(-660 2560);
DISPLAY 0.617021 (-660 2560);
PAINT ORANGE (-660 2560);
FORCEPROP 2 LASTPIN (-650 2900) $PN 142
J 2
(-660 2910);
DISPLAY 0.617021 (-660 2910);
PAINT ORANGE (-660 2910);
FORCEPROP 2 LASTPIN (-650 2850) $PN 143
J 2
(-660 2860);
DISPLAY 0.617021 (-660 2860);
PAINT ORANGE (-660 2860);
FORCEPROP 2 LASTPIN (-650 2800) $PN 288
J 2
(-660 2810);
DISPLAY 0.617021 (-660 2810);
PAINT ORANGE (-660 2810);
FORCEPROP 2 LASTPIN (-650 2750) $PN 286
J 2
(-660 2760);
DISPLAY 0.617021 (-660 2760);
PAINT ORANGE (-660 2760);
FORCEPROP 2 LASTPIN (-650 2700) $PN 287
J 2
(-660 2710);
DISPLAY 0.617021 (-660 2710);
PAINT ORANGE (-660 2710);
FORCEPROP 2 LASTPIN (-650 2450) $PN 59
J 2
(-660 2460);
DISPLAY 0.617021 (-660 2460);
PAINT ORANGE (-660 2460);
FORCEPROP 2 LASTPIN (-650 2400) $PN 61
J 2
(-660 2410);
DISPLAY 0.617021 (-660 2410);
PAINT ORANGE (-660 2410);
FORCEPROP 2 LASTPIN (-650 2350) $PN 64
J 2
(-660 2360);
DISPLAY 0.617021 (-660 2360);
PAINT ORANGE (-660 2360);
FORCEPROP 2 LASTPIN (-650 2300) $PN 67
J 2
(-660 2310);
DISPLAY 0.617021 (-660 2310);
PAINT ORANGE (-660 2310);
FORCEPROP 2 LASTPIN (-650 2250) $PN 70
J 2
(-660 2260);
DISPLAY 0.617021 (-660 2260);
PAINT ORANGE (-660 2260);
FORCEPROP 2 LASTPIN (-650 2200) $PN 73
J 2
(-660 2210);
DISPLAY 0.617021 (-660 2210);
PAINT ORANGE (-660 2210);
FORCEPROP 2 LASTPIN (-650 2150) $PN 76
J 2
(-660 2160);
DISPLAY 0.617021 (-660 2160);
PAINT ORANGE (-660 2160);
FORCEPROP 2 LASTPIN (-650 2100) $PN 80
J 2
(-660 2110);
DISPLAY 0.617021 (-660 2110);
PAINT ORANGE (-660 2110);
FORCEPROP 2 LASTPIN (-650 2050) $PN 83
J 2
(-660 2060);
DISPLAY 0.617021 (-660 2060);
PAINT ORANGE (-660 2060);
FORCEPROP 2 LASTPIN (-650 2000) $PN 85
J 2
(-660 2010);
DISPLAY 0.617021 (-660 2010);
PAINT ORANGE (-660 2010);
FORCEPROP 2 LASTPIN (-650 1950) $PN 88
J 2
(-660 1960);
DISPLAY 0.617021 (-660 1960);
PAINT ORANGE (-660 1960);
FORCEPROP 2 LASTPIN (-650 1900) $PN 90
J 2
(-660 1910);
DISPLAY 0.617021 (-660 1910);
PAINT ORANGE (-660 1910);
FORCEPROP 2 LASTPIN (-650 1850) $PN 92
J 2
(-660 1860);
DISPLAY 0.617021 (-660 1860);
PAINT ORANGE (-660 1860);
FORCEPROP 2 LASTPIN (-650 1800) $PN 204
J 2
(-660 1810);
DISPLAY 0.617021 (-660 1810);
PAINT ORANGE (-660 1810);
FORCEPROP 2 LASTPIN (-650 1750) $PN 206
J 2
(-660 1760);
DISPLAY 0.617021 (-660 1760);
PAINT ORANGE (-660 1760);
FORCEPROP 2 LASTPIN (-650 1700) $PN 209
J 2
(-660 1710);
DISPLAY 0.617021 (-660 1710);
PAINT ORANGE (-660 1710);
FORCEPROP 2 LASTPIN (-650 1650) $PN 212
J 2
(-660 1660);
DISPLAY 0.617021 (-660 1660);
PAINT ORANGE (-660 1660);
FORCEPROP 2 LASTPIN (-650 1600) $PN 215
J 2
(-660 1610);
DISPLAY 0.617021 (-660 1610);
PAINT ORANGE (-660 1610);
FORCEPROP 2 LASTPIN (-650 1550) $PN 217
J 2
(-660 1560);
DISPLAY 0.617021 (-660 1560);
PAINT ORANGE (-660 1560);
FORCEPROP 2 LASTPIN (-650 1500) $PN 220
J 2
(-660 1510);
DISPLAY 0.617021 (-660 1510);
PAINT ORANGE (-660 1510);
FORCEPROP 2 LASTPIN (-650 1450) $PN 223
J 2
(-660 1460);
DISPLAY 0.617021 (-660 1460);
PAINT ORANGE (-660 1460);
FORCEPROP 2 LASTPIN (-650 1400) $PN 226
J 2
(-660 1410);
DISPLAY 0.617021 (-660 1410);
PAINT ORANGE (-660 1410);
FORCEPROP 2 LASTPIN (-650 1350) $PN 229
J 2
(-660 1360);
DISPLAY 0.617021 (-660 1360);
PAINT ORANGE (-660 1360);
FORCEPROP 2 LASTPIN (-650 1300) $PN 231
J 2
(-660 1310);
DISPLAY 0.617021 (-660 1310);
PAINT ORANGE (-660 1310);
FORCEPROP 2 LASTPIN (-650 1250) $PN 233
J 2
(-660 1260);
DISPLAY 0.617021 (-660 1260);
PAINT ORANGE (-660 1260);
FORCEPROP 2 LASTPIN (-650 1200) $PN 236
J 2
(-660 1210);
DISPLAY 0.617021 (-660 1210);
PAINT ORANGE (-660 1210);
FORCEPROP 2 LASTPIN (350 2900) $PN 1
J 0
(360 2910);
DISPLAY 0.617021 (360 2910);
PAINT ORANGE (360 2910);
FORCEPROP 2 LASTPIN (350 2850) $PN 145
J 0
(360 2860);
DISPLAY 0.617021 (360 2860);
PAINT ORANGE (360 2860);
FORCEPROP 1 LAST PACK_TYPE PIP
J 0
(-600 3200);
PAINT SKYBLUE (-600 3200);
DISPLAY INVISIBLE (-600 3200);
FORCEPROP 2 LAST BOM_COST MEM
J 0
(-150 2050);
PAINT ORANGE (-150 2050);
DISPLAY INVISIBLE (-150 2050);
FORCEPROP 2 LAST CDS_LIB mstr_sconn
J 0
(-150 2050);
PAINT ORANGE (-150 2050);
DISPLAY INVISIBLE (-150 2050);
FORCEPROP 2 LAST SEC_TYPE PIP
J 0
(-600 3200);
DISPLAY 1.021277 (-600 3200);
PAINT ORANGE (-600 3200);
DISPLAY INVISIBLE (-600 3200);
FORCEPROP 2 LAST SEC 4
J 0
(-600 3200);
DISPLAY 0.680851 (-600 3200);
PAINT MONO (-600 3200);
DISPLAY INVISIBLE (-600 3200);
FORCEPROP 2 LAST CDS_LOCATION J4A2
J 0
(-600 3150);
DISPLAY 0.617021 (-600 3150);
PAINT AQUA (-600 3150);
DISPLAY INVISIBLE (-600 3150);
FORCEPROP 1 LAST PATH I167
J 0
(-150 3100);
PAINT GREEN (-150 3100);
DISPLAY INVISIBLE (-150 3100);
FORCEPROP 2 LAST ROOM DDR4_CH_E
J 0
(-150 2050);
PAINT ORANGE (-150 2050);
DISPLAY INVISIBLE (-150 2050);
FORCEADD GND..1
R 2
(2500 1200);
FORCEPROP 3 LASTPIN (2500 1250) SIG_NAME GND\g
J 0
(2510 1260);
DISPLAY 0.659574 (2510 1260);
PAINT MONO (2510 1260);
DISPLAY INVISIBLE (2510 1260);
FORCEPROP 1 LAST VOLTAGE 0
J 0
(2500 1200);
PAINT SKYBLUE (2500 1200);
DISPLAY INVISIBLE (2500 1200);
FORCEPROP 1 LAST SIZE 1B
J 2
(2425 1150);
DISPLAY 1.170213 (2425 1150);
PAINT GREEN (2425 1150);
DISPLAY INVISIBLE (2425 1150);
FORCEPROP 2 LAST CDS_LIB mstr_symbols
J 0
(2500 1200);
DISPLAY 0.787234 (2500 1200);
PAINT MONO (2500 1200);
DISPLAY INVISIBLE (2500 1200);
FORCEPROP 2 LAST BOM_COST MEM
J 0
(2500 1205);
PAINT ORANGE (2500 1205);
DISPLAY INVISIBLE (2500 1205);
FORCEPROP 1 LAST BODY_TYPE PLUMBING
J 2
(2545 1157);
DISPLAY 0.340426 (2545 1157);
PAINT GREEN (2545 1157);
DISPLAY INVISIBLE (2545 1157);
FORCEPROP 1 LAST PATH I168
J 2
(2425 1200);
DISPLAY 1.404255 (2425 1200);
PAINT GREEN (2425 1200);
DISPLAY INVISIBLE (2425 1200);
FORCEPROP 2 LAST ROOM DDR4_CH_B
J 0
(2500 1205);
PAINT ORANGE (2500 1205);
DISPLAY INVISIBLE (2500 1205);
FORCEPROP 1 LAST HDL_POWER GND
J 2
(2500 1350);
DISPLAY 0.553191 (2500 1350);
PAINT GREEN (2500 1350);
DISPLAY INVISIBLE (2500 1350);
FORCEADD OFFPAGE..1
(-3700 1850);
FORCEPROP 2 LAST $XR0 99 
J 0
(-3981 1850);
DISPLAY 0.638298 (-3981 1850);
PAINT MONO (-3981 1850);
FORCEPROP 2 LAST $XR1 49 
J 0
(-4071 1850);
DISPLAY 0.638298 (-4071 1850);
PAINT MONO (-4071 1850);
FORCEPROP 2 LAST $XR2 50 
J 0
(-4161 1850);
DISPLAY 0.638298 (-4161 1850);
PAINT MONO (-4161 1850);
FORCEPROP 2 LAST $XR3 52 
J 0
(-4251 1850);
DISPLAY 0.638298 (-4251 1850);
PAINT MONO (-4251 1850);
FORCEPROP 2 LAST $XR4 53 
J 0
(-4341 1850);
DISPLAY 0.638298 (-4341 1850);
PAINT MONO (-4341 1850);
FORCEPROP 2 LAST $XR5 54 
J 0
(-4431 1850);
DISPLAY 0.638298 (-4431 1850);
PAINT MONO (-4431 1850);
FORCEPROP 2 LAST CDS_LIB mstr_standard
J 0
(-3700 1850);
DISPLAY 0.787234 (-3700 1850);
PAINT MONO (-3700 1850);
DISPLAY INVISIBLE (-3700 1850);
FORCEPROP 1 LAST OFFPAGE TRUE
J 0
(-3375 1725);
DISPLAY 0.936170 (-3375 1725);
PAINT GREEN (-3375 1725);
DISPLAY INVISIBLE (-3375 1725);
FORCEPROP 1 LAST COMMENT_BODY TRUE
J 0
(-3575 1750);
DISPLAY 0.936170 (-3575 1750);
PAINT GREEN (-3575 1750);
DISPLAY INVISIBLE (-3575 1750);
FORCEPROP 2 LAST PATH I169
J 0
(-3975 1900);
DISPLAY 0.787234 (-3975 1900);
PAINT ORANGE (-3975 1900);
DISPLAY INVISIBLE (-3975 1900);
FORCEADD PVTT_DEF..1
(-1000 2750);
FORCEPROP 3 LASTPIN (-1000 2700) SIG_NAME PVTT_DEF\g
J 0
(-990 2710);
DISPLAY 0.659574 (-990 2710);
PAINT MONO (-990 2710);
DISPLAY INVISIBLE (-990 2710);
FORCEPROP 1 LAST VOLTAGE 0.6V
J 0
(-1045 2707);
DISPLAY 0.340426 (-1045 2707);
PAINT SKYBLUE (-1045 2707);
DISPLAY INVISIBLE (-1045 2707);
FORCEPROP 2 LAST BOM_COST MEM
J 0
(-1000 2755);
PAINT ORANGE (-1000 2755);
DISPLAY INVISIBLE (-1000 2755);
FORCEPROP 2 LAST CDS_LIB mstr_symbols
J 0
(-1000 2750);
PAINT ORANGE (-1000 2750);
DISPLAY INVISIBLE (-1000 2750);
FORCEPROP 1 LAST BODY_TYPE PLUMBING
J 0
(-1045 2707);
DISPLAY 0.340426 (-1045 2707);
PAINT GREEN (-1045 2707);
DISPLAY INVISIBLE (-1045 2707);
FORCEPROP 1 LAST PATH I17
J 0
(-950 2775);
DISPLAY 0.872340 (-950 2775);
PAINT AQUA (-950 2775);
DISPLAY INVISIBLE (-950 2775);
FORCEPROP 2 LAST ROOM DDR4_CH_B
J 0
(-1000 2850);
DISPLAY 0.787234 (-1000 2850);
PAINT ORANGE (-1000 2850);
DISPLAY INVISIBLE (-1000 2850);
FORCEPROP 1 LAST HDL_POWER PVTT_DEF
J 1
(-1000 2800);
DISPLAY 0.872340 (-1000 2800);
PAINT GREEN (-1000 2800);
DISPLAY INVISIBLE (-1000 2800);
FORCEADD OFFPAGE..5
(-4075 2600);
FORCEPROP 2 LAST $XR0 43 
J 0
(-4299 2600);
DISPLAY 0.638298 (-4299 2600);
PAINT MONO (-4299 2600);
FORCEPROP 2 LAST $XR1 44 
J 0
(-4389 2600);
DISPLAY 0.638298 (-4389 2600);
PAINT MONO (-4389 2600);
FORCEPROP 2 LAST $XR2 45 
J 0
(-4479 2600);
DISPLAY 0.638298 (-4479 2600);
PAINT MONO (-4479 2600);
FORCEPROP 2 LAST $XR3 46 
J 0
(-4569 2600);
DISPLAY 0.638298 (-4569 2600);
PAINT MONO (-4569 2600);
FORCEPROP 2 LAST $XR4 47 
J 0
(-4659 2600);
DISPLAY 0.638298 (-4659 2600);
PAINT MONO (-4659 2600);
FORCEPROP 2 LAST $XR5 48 
J 0
(-4749 2600);
DISPLAY 0.638298 (-4749 2600);
PAINT MONO (-4749 2600);
FORCEPROP 2 LAST $XR6 49 
J 0
(-4839 2600);
DISPLAY 0.638298 (-4839 2600);
PAINT MONO (-4839 2600);
FORCEPROP 2 LAST $XR7 50 
J 0
(-4929 2600);
DISPLAY 0.638298 (-4929 2600);
PAINT MONO (-4929 2600);
FORCEPROP 2 LAST $XR8 52 
J 0
(-5019 2600);
DISPLAY 0.638298 (-5019 2600);
PAINT MONO (-5019 2600);
FORCEPROP 2 LAST $XR9 53 
J 0
(-5109 2600);
DISPLAY 0.638298 (-5109 2600);
PAINT MONO (-5109 2600);
FORCEPROP 2 LAST $XR10 54 
J 0
(-4299 2564);
DISPLAY 0.638298 (-4299 2564);
PAINT MONO (-4299 2564);
FORCEPROP 2 LAST $XR11 77 
J 0
(-4389 2564);
DISPLAY 0.638298 (-4389 2564);
PAINT MONO (-4389 2564);
FORCEPROP 2 LAST $XR12 78 
J 0
(-4479 2564);
DISPLAY 0.638298 (-4479 2564);
PAINT MONO (-4479 2564);
FORCEPROP 2 LAST $XR13 79 
J 0
(-4569 2564);
DISPLAY 0.638298 (-4569 2564);
PAINT MONO (-4569 2564);
FORCEPROP 2 LAST $XR14 80 
J 0
(-4659 2564);
DISPLAY 0.638298 (-4659 2564);
PAINT MONO (-4659 2564);
FORCEPROP 2 LAST $XR15 81 
J 0
(-4749 2564);
DISPLAY 0.638298 (-4749 2564);
PAINT MONO (-4749 2564);
FORCEPROP 2 LAST $XR16 82 
J 0
(-4839 2564);
DISPLAY 0.638298 (-4839 2564);
PAINT MONO (-4839 2564);
FORCEPROP 2 LAST $XR17 83 
J 0
(-4929 2564);
DISPLAY 0.638298 (-4929 2564);
PAINT MONO (-4929 2564);
FORCEPROP 2 LAST $XR18 84 
J 0
(-5019 2564);
DISPLAY 0.638298 (-5019 2564);
PAINT MONO (-5019 2564);
FORCEPROP 2 LAST $XR19 85 
J 0
(-5109 2564);
DISPLAY 0.638298 (-5109 2564);
PAINT MONO (-5109 2564);
FORCEPROP 2 LAST $XR20 86 
J 0
(-4299 2636);
DISPLAY 0.638298 (-4299 2636);
PAINT MONO (-4299 2636);
FORCEPROP 2 LAST $XR21 87 
J 0
(-4389 2636);
DISPLAY 0.638298 (-4389 2636);
PAINT MONO (-4389 2636);
FORCEPROP 2 LAST $XR22 88 
J 0
(-4479 2636);
DISPLAY 0.638298 (-4479 2636);
PAINT MONO (-4479 2636);
FORCEPROP 2 LAST $XR23 94 
J 0
(-4569 2636);
DISPLAY 0.638298 (-4569 2636);
PAINT MONO (-4569 2636);
FORCEPROP 2 LAST CDS_LIB mstr_standard
J 0
(-4075 2600);
DISPLAY 0.787234 (-4075 2600);
PAINT MONO (-4075 2600);
DISPLAY INVISIBLE (-4075 2600);
FORCEPROP 1 LAST OFFPAGE TRUE
J 0
(-3750 2475);
DISPLAY 1.404255 (-3750 2475);
PAINT GREEN (-3750 2475);
DISPLAY INVISIBLE (-3750 2475);
FORCEPROP 1 LAST COMMENT_BODY TRUE
J 0
(-3975 2525);
DISPLAY 1.404255 (-3975 2525);
PAINT GREEN (-3975 2525);
DISPLAY INVISIBLE (-3975 2525);
FORCEPROP 2 LAST PATH I171
J 0
(-4375 2650);
DISPLAY 0.787234 (-4375 2650);
PAINT ORANGE (-4375 2650);
DISPLAY INVISIBLE (-4375 2650);
FORCEADD OFFPAGE..6
(-3700 1900);
FORCEPROP 2 LAST $XR0 49 
J 0
(-3979 1900);
DISPLAY 0.638298 (-3979 1900);
PAINT MONO (-3979 1900);
FORCEPROP 2 LAST $XR1 50 
J 0
(-4069 1900);
DISPLAY 0.638298 (-4069 1900);
PAINT MONO (-4069 1900);
FORCEPROP 2 LAST $XR2 52 
J 0
(-4159 1900);
DISPLAY 0.638298 (-4159 1900);
PAINT MONO (-4159 1900);
FORCEPROP 2 LAST $XR3 53 
J 0
(-4249 1900);
DISPLAY 0.638298 (-4249 1900);
PAINT MONO (-4249 1900);
FORCEPROP 2 LAST $XR4 54 
J 0
(-4339 1900);
DISPLAY 0.638298 (-4339 1900);
PAINT MONO (-4339 1900);
FORCEPROP 2 LAST $XR5 99 
J 0
(-4429 1900);
DISPLAY 0.638298 (-4429 1900);
PAINT MONO (-4429 1900);
FORCEPROP 2 LASTPIN (-3650 1900) SIG_NAME SMB_DDR_DEF_VPP_SDA
J 0
(-3610 1910);
DISPLAY 0.617021 (-3610 1910);
PAINT ORANGE (-3610 1910);
FORCEPROP 2 LAST CDS_LIB mstr_standard
J 0
(-3700 1900);
DISPLAY 0.787234 (-3700 1900);
PAINT MONO (-3700 1900);
DISPLAY INVISIBLE (-3700 1900);
FORCEPROP 1 LAST OFFPAGE TRUE
J 0
(-3375 1775);
DISPLAY 0.936170 (-3375 1775);
PAINT GREEN (-3375 1775);
DISPLAY INVISIBLE (-3375 1775);
FORCEPROP 1 LAST COMMENT_BODY TRUE
J 0
(-3600 1825);
DISPLAY 0.936170 (-3600 1825);
PAINT GREEN (-3600 1825);
DISPLAY INVISIBLE (-3600 1825);
FORCEPROP 2 LAST PATH I172
J 0
(-4000 1950);
DISPLAY 0.787234 (-4000 1950);
PAINT ORANGE (-4000 1950);
DISPLAY INVISIBLE (-4000 1950);
FORCEADD GND..1
R 2
(-5200 1800);
FORCEPROP 3 LASTPIN (-5200 1850) SIG_NAME GND\g
J 0
(-5190 1860);
DISPLAY 0.659574 (-5190 1860);
PAINT MONO (-5190 1860);
DISPLAY INVISIBLE (-5190 1860);
FORCEPROP 1 LAST VOLTAGE 0
J 0
(-5200 1800);
PAINT SKYBLUE (-5200 1800);
DISPLAY INVISIBLE (-5200 1800);
FORCEPROP 1 LAST SIZE 1B
J 2
(-5275 1750);
DISPLAY 1.170213 (-5275 1750);
PAINT GREEN (-5275 1750);
DISPLAY INVISIBLE (-5275 1750);
FORCEPROP 2 LAST CDS_LIB mstr_symbols
J 0
(-5200 1800);
DISPLAY 0.787234 (-5200 1800);
PAINT MONO (-5200 1800);
DISPLAY INVISIBLE (-5200 1800);
FORCEPROP 2 LAST BOM_COST MEM
J 0
(-5200 1805);
PAINT ORANGE (-5200 1805);
DISPLAY INVISIBLE (-5200 1805);
FORCEPROP 1 LAST BODY_TYPE PLUMBING
J 2
(-5155 1757);
DISPLAY 0.340426 (-5155 1757);
PAINT GREEN (-5155 1757);
DISPLAY INVISIBLE (-5155 1757);
FORCEPROP 1 LAST PATH I174
J 2
(-5275 1800);
DISPLAY 1.404255 (-5275 1800);
PAINT GREEN (-5275 1800);
DISPLAY INVISIBLE (-5275 1800);
FORCEPROP 2 LAST ROOM DDR4_CH_B
J 0
(-5200 1805);
PAINT ORANGE (-5200 1805);
DISPLAY INVISIBLE (-5200 1805);
FORCEPROP 1 LAST HDL_POWER GND
J 2
(-5200 1950);
DISPLAY 0.553191 (-5200 1950);
PAINT GREEN (-5200 1950);
DISPLAY INVISIBLE (-5200 1950);
FORCEADD CAP_A..1
R 2
(-4650 1550);
FORCEPROP 1 LAST LOCATION C6L6
J 2
(-4700 1650);
DISPLAY 0.617021 (-4700 1650);
PAINT AQUA (-4700 1650);
FORCEPROP 1 LAST PART_NUMBER A36096-045
J 2
(-4700 1400);
DISPLAY 0.617021 (-4700 1400);
PAINT BLUE (-4700 1400);
FORCEPROP 1 LAST VALUE 0.01UF
J 2
(-4700 1600);
DISPLAY 0.617021 (-4700 1600);
PAINT SKYBLUE (-4700 1600);
FORCEPROP 1 LAST TOLERANCE 10%
J 2
(-4700 1500);
DISPLAY 0.617021 (-4700 1500);
PAINT SKYBLUE (-4700 1500);
FORCEPROP 1 LAST PACK_TYPE 0402V
J 2
(-4700 1350);
DISPLAY 0.617021 (-4700 1350);
PAINT SKYBLUE (-4700 1350);
FORCEPROP 1 LAST VOLTAGE 25V
J 2
(-4700 1550);
DISPLAY 0.617021 (-4700 1550);
PAINT SKYBLUE (-4700 1550);
FORCEPROP 1 LAST MATERIAL X7R
J 2
(-4700 1450);
DISPLAY 0.617021 (-4700 1450);
PAINT SKYBLUE (-4700 1450);
FORCEPROP 2 LAST CDS_LOCATION C6L6
J 2
(-4700 1650);
DISPLAY 0.617021 (-4700 1650);
PAINT AQUA (-4700 1650);
DISPLAY INVISIBLE (-4700 1650);
FORCEPROP 2 LAST BOM_COST MEM
J 0
(-4650 1550);
PAINT ORANGE (-4650 1550);
DISPLAY INVISIBLE (-4650 1550);
FORCEPROP 2 LAST CDS_LIB dev_discrete
J 0
(-4650 1550);
PAINT ORANGE (-4650 1550);
DISPLAY INVISIBLE (-4650 1550);
FORCEPROP 2 LAST CDS_SEC 1
J 2
(-4700 1750);
PAINT MONO (-4700 1750);
DISPLAY INVISIBLE (-4700 1750);
FORCEPROP 2 LAST $SEC 1
J 0
(-4700 1750);
PAINT MONO (-4700 1750);
DISPLAY INVISIBLE (-4700 1750);
FORCEPROP 1 LAST PATH I175
J 2
(-4700 1700);
DISPLAY 0.978723 (-4700 1700);
PAINT WHITE (-4700 1700);
DISPLAY INVISIBLE (-4700 1700);
FORCEPROP 2 LAST ROOM DDR4_CH_E
J 0
(-4650 1550);
PAINT ORANGE (-4650 1550);
DISPLAY INVISIBLE (-4650 1550);
FORCEPROP 1 LASTPIN (-4650 1650) $PN 1
J 2
(-4660 1630);
DISPLAY 0.787234 (-4660 1630);
PAINT ORANGE (-4660 1630);
DISPLAY INVISIBLE (-4660 1630);
FORCEPROP 1 LASTPIN (-4650 1450) $PN 2
J 2
(-4660 1430);
DISPLAY 0.787234 (-4660 1430);
PAINT ORANGE (-4660 1430);
DISPLAY INVISIBLE (-4660 1430);
FORCEADD GND..1
R 2
(-4650 1300);
FORCEPROP 3 LASTPIN (-4650 1350) SIG_NAME GND\g
J 0
(-4640 1360);
DISPLAY 0.659574 (-4640 1360);
PAINT MONO (-4640 1360);
DISPLAY INVISIBLE (-4640 1360);
FORCEPROP 1 LAST VOLTAGE 0
J 0
(-4650 1300);
PAINT SKYBLUE (-4650 1300);
DISPLAY INVISIBLE (-4650 1300);
FORCEPROP 2 LAST BOM_COST MEM
J 0
(-4650 1305);
PAINT ORANGE (-4650 1305);
DISPLAY INVISIBLE (-4650 1305);
FORCEPROP 2 LAST CDS_LIB mstr_symbols
J 2
(-4650 1300);
PAINT ORANGE (-4650 1300);
DISPLAY INVISIBLE (-4650 1300);
FORCEPROP 1 LAST SIZE 1B
J 2
(-4725 1250);
DISPLAY 1.787234 (-4725 1250);
PAINT GREEN (-4725 1250);
DISPLAY INVISIBLE (-4725 1250);
FORCEPROP 1 LAST BODY_TYPE PLUMBING
J 2
(-4605 1257);
DISPLAY 0.340426 (-4605 1257);
PAINT GREEN (-4605 1257);
DISPLAY INVISIBLE (-4605 1257);
FORCEPROP 1 LAST PATH I176
J 2
(-4725 1300);
DISPLAY 1.404255 (-4725 1300);
PAINT GREEN (-4725 1300);
DISPLAY INVISIBLE (-4725 1300);
FORCEPROP 2 LAST ROOM DDR4_CH_B
J 0
(-4650 1305);
PAINT ORANGE (-4650 1305);
DISPLAY INVISIBLE (-4650 1305);
FORCEPROP 1 LAST HDL_POWER GND
J 2
(-4650 1450);
DISPLAY 1.404255 (-4650 1450);
PAINT GREEN (-4650 1450);
DISPLAY INVISIBLE (-4650 1450);
FORCEADD PVPP_DEF..1
(-850 3050);
FORCEPROP 3 LASTPIN (-850 3000) SIG_NAME PVPP_DEF\g
J 0
(-840 3010);
DISPLAY 0.659574 (-840 3010);
PAINT MONO (-840 3010);
DISPLAY INVISIBLE (-840 3010);
FORCEPROP 1 LAST VOLTAGE 2.5V
J 0
(-895 3007);
DISPLAY 0.340426 (-895 3007);
PAINT SKYBLUE (-895 3007);
DISPLAY INVISIBLE (-895 3007);
FORCEPROP 0 LAST BOM_COST MEM
J 0
(-850 3150);
PAINT ORANGE (-850 3150);
DISPLAY INVISIBLE (-850 3150);
FORCEPROP 2 LAST CDS_LIB mstr_symbols
J 0
(-850 3050);
PAINT ORANGE (-850 3050);
DISPLAY INVISIBLE (-850 3050);
FORCEPROP 1 LAST BODY_TYPE PLUMBING
J 0
(-895 3007);
DISPLAY 0.340426 (-895 3007);
PAINT GREEN (-895 3007);
DISPLAY INVISIBLE (-895 3007);
FORCEPROP 1 LAST PATH I177
J 0
(-800 3075);
DISPLAY 0.872340 (-800 3075);
PAINT AQUA (-800 3075);
DISPLAY INVISIBLE (-800 3075);
FORCEPROP 2 LAST ROOM DDR4_CH_B
J 0
(-850 3150);
PAINT ORANGE (-850 3150);
DISPLAY INVISIBLE (-850 3150);
FORCEPROP 1 LAST HDL_POWER PVPP_DEF
J 1
(-850 3100);
DISPLAY 0.872340 (-850 3100);
PAINT GREEN (-850 3100);
DISPLAY INVISIBLE (-850 3100);
FORCEADD PVPP_DEF..1
(-5200 2250);
FORCEPROP 3 LASTPIN (-5200 2200) SIG_NAME PVPP_DEF\g
J 0
(-5190 2210);
DISPLAY 0.659574 (-5190 2210);
PAINT MONO (-5190 2210);
DISPLAY INVISIBLE (-5190 2210);
FORCEPROP 1 LAST VOLTAGE 2.5V
J 0
(-5245 2207);
DISPLAY 0.340426 (-5245 2207);
PAINT SKYBLUE (-5245 2207);
DISPLAY INVISIBLE (-5245 2207);
FORCEPROP 0 LAST BOM_COST MEM
J 0
(-5200 2350);
PAINT ORANGE (-5200 2350);
DISPLAY INVISIBLE (-5200 2350);
FORCEPROP 2 LAST CDS_LIB mstr_symbols
J 0
(-5200 2250);
PAINT ORANGE (-5200 2250);
DISPLAY INVISIBLE (-5200 2250);
FORCEPROP 1 LAST BODY_TYPE PLUMBING
J 0
(-5245 2207);
DISPLAY 0.340426 (-5245 2207);
PAINT GREEN (-5245 2207);
DISPLAY INVISIBLE (-5245 2207);
FORCEPROP 1 LAST PATH I178
J 0
(-5150 2275);
DISPLAY 0.872340 (-5150 2275);
PAINT AQUA (-5150 2275);
DISPLAY INVISIBLE (-5150 2275);
FORCEPROP 2 LAST ROOM DDR4_CH_B
J 0
(-5200 2350);
PAINT ORANGE (-5200 2350);
DISPLAY INVISIBLE (-5200 2350);
FORCEPROP 1 LAST HDL_POWER PVPP_DEF
J 1
(-5200 2300);
DISPLAY 0.872340 (-5200 2300);
PAINT GREEN (-5200 2300);
DISPLAY INVISIBLE (-5200 2300);
FORCEADD OFFPAGE..1
(-3750 1450);
FORCEPROP 2 LAST $XR0 89 
J 0
(-3971 1450);
DISPLAY 0.638298 (-3971 1450);
PAINT MONO (-3971 1450);
FORCEPROP 2 LAST $XR1 49 
J 0
(-4061 1450);
DISPLAY 0.638298 (-4061 1450);
PAINT MONO (-4061 1450);
FORCEPROP 2 LAST $XR2 50 
J 0
(-4151 1450);
DISPLAY 0.638298 (-4151 1450);
PAINT MONO (-4151 1450);
FORCEPROP 2 LAST $XR3 52 
J 0
(-4241 1450);
DISPLAY 0.638298 (-4241 1450);
PAINT MONO (-4241 1450);
FORCEPROP 2 LAST $XR4 53 
J 0
(-4331 1450);
DISPLAY 0.638298 (-4331 1450);
PAINT MONO (-4331 1450);
FORCEPROP 2 LAST $XR5 54 
J 0
(-4421 1450);
DISPLAY 0.638298 (-4421 1450);
PAINT MONO (-4421 1450);
FORCEPROP 2 LAST CDS_LIB mstr_standard
J 0
(-3750 1450);
PAINT ORANGE (-3750 1450);
DISPLAY INVISIBLE (-3750 1450);
FORCEPROP 1 LAST OFFPAGE TRUE
J 0
(-3425 1325);
DISPLAY 0.936170 (-3425 1325);
PAINT GREEN (-3425 1325);
DISPLAY INVISIBLE (-3425 1325);
FORCEPROP 1 LAST COMMENT_BODY TRUE
J 0
(-3625 1350);
DISPLAY 0.936170 (-3625 1350);
PAINT GREEN (-3625 1350);
DISPLAY INVISIBLE (-3625 1350);
FORCEPROP 2 LAST PATH I179
J 0
(-3700 1525);
PAINT ORANGE (-3700 1525);
DISPLAY INVISIBLE (-3700 1525);
FORCEADD TAP..6
(-3500 3700);
FORCEPROP 3 LASTPIN (-3450 3700) SIG_NAME M_E_CLK_DP<1>
J 0
(-3440 3710);
DISPLAY 0.659574 (-3440 3710);
PAINT MONO (-3440 3710);
DISPLAY INVISIBLE (-3440 3710);
FORCEPROP 1 LASTPIN (-3450 3700) BN 1
J 0
(-3502 3708);
DISPLAY 0.617021 (-3502 3708);
PAINT PINK (-3502 3708);
FORCEPROP 2 LAST CDS_LIB mstr_standard
J 0
(-3500 3700);
PAINT MONO (-3500 3700);
DISPLAY INVISIBLE (-3500 3700);
FORCEPROP 1 LAST BODY_TYPE PLUMBING
J 0
(-3500 3650);
DISPLAY 1.234043 (-3500 3650);
PAINT GREEN (-3500 3650);
DISPLAY INVISIBLE (-3500 3650);
FORCEPROP 1 LAST HDL_TAP TRUE
J 0
(-3175 3575);
DISPLAY 1.234043 (-3175 3575);
PAINT GREEN (-3175 3575);
DISPLAY INVISIBLE (-3175 3575);
FORCEPROP 1 LAST PATH I183
J 0
(-3502 3700);
DISPLAY 0.872340 (-3502 3700);
PAINT GREEN (-3502 3700);
DISPLAY INVISIBLE (-3502 3700);
FORCEADD TAP..6
(-3650 3650);
FORCEPROP 3 LASTPIN (-3600 3650) SIG_NAME M_E_CLK_DN<1>
J 0
(-3590 3660);
DISPLAY 0.659574 (-3590 3660);
PAINT MONO (-3590 3660);
DISPLAY INVISIBLE (-3590 3660);
FORCEPROP 1 LASTPIN (-3600 3650) BN 1
J 0
(-3652 3658);
DISPLAY 0.617021 (-3652 3658);
PAINT PINK (-3652 3658);
FORCEPROP 2 LAST CDS_LIB mstr_standard
J 0
(-3650 3650);
PAINT MONO (-3650 3650);
DISPLAY INVISIBLE (-3650 3650);
FORCEPROP 1 LAST BODY_TYPE PLUMBING
J 0
(-3650 3600);
DISPLAY 1.234043 (-3650 3600);
PAINT GREEN (-3650 3600);
DISPLAY INVISIBLE (-3650 3600);
FORCEPROP 1 LAST HDL_TAP TRUE
J 0
(-3325 3525);
DISPLAY 1.234043 (-3325 3525);
PAINT GREEN (-3325 3525);
DISPLAY INVISIBLE (-3325 3525);
FORCEPROP 1 LAST PATH I184
J 0
(-3652 3650);
DISPLAY 0.872340 (-3652 3650);
PAINT GREEN (-3652 3650);
DISPLAY INVISIBLE (-3652 3650);
FORCEADD P12V_NVDIMM_DEF..1
(550 3125);
FORCEPROP 3 LASTPIN (550 3075) SIG_NAME P12V_NVDIMM_DEF\g
J 0
(560 3085);
DISPLAY 0.659574 (560 3085);
PAINT MONO (560 3085);
DISPLAY INVISIBLE (560 3085);
FORCEPROP 1 LAST VOLTAGE 12.0
J 0
(505 3082);
DISPLAY 0.340426 (505 3082);
PAINT SKYBLUE (505 3082);
DISPLAY INVISIBLE (505 3082);
FORCEPROP 2 LAST CDS_LIB mstr_symbols
J 0
(550 3125);
PAINT ORANGE (550 3125);
DISPLAY INVISIBLE (550 3125);
FORCEPROP 1 LAST BODY_TYPE PLUMBING
J 0
(505 3082);
DISPLAY 0.340426 (505 3082);
PAINT GREEN (505 3082);
DISPLAY INVISIBLE (505 3082);
FORCEPROP 1 LAST PATH I185
J 0
(600 3150);
DISPLAY 0.872340 (600 3150);
PAINT AQUA (600 3150);
DISPLAY INVISIBLE (600 3150);
FORCEPROP 1 LAST HDL_POWER P12V_NVDIMM_DEF
J 1
(550 3175);
DISPLAY 0.872340 (550 3175);
PAINT GREEN (550 3175);
DISPLAY INVISIBLE (550 3175);
FORCEADD TAP..6
R 2
(900 4500);
FORCEPROP 3 LASTPIN (850 4500) SIG_NAME M_E_DQS_DN<11>
J 0
(860 4510);
DISPLAY 0.659574 (860 4510);
PAINT MONO (860 4510);
DISPLAY INVISIBLE (860 4510);
FORCEPROP 1 LASTPIN (850 4500) BN 11
J 2
(900 4510);
DISPLAY 0.617021 (900 4510);
PAINT PINK (900 4510);
FORCEPROP 2 LAST CDS_LIB mstr_standard
J 0
(900 4500);
DISPLAY 0.787234 (900 4500);
PAINT MONO (900 4500);
DISPLAY INVISIBLE (900 4500);
FORCEPROP 1 LAST BODY_TYPE PLUMBING
J 2
(900 4450);
DISPLAY 1.234043 (900 4450);
PAINT GREEN (900 4450);
DISPLAY INVISIBLE (900 4450);
FORCEPROP 1 LAST HDL_TAP TRUE
J 2
(575 4375);
DISPLAY 1.234043 (575 4375);
PAINT GREEN (575 4375);
DISPLAY INVISIBLE (575 4375);
FORCEPROP 1 LAST PATH I19
J 2
(900 4500);
DISPLAY 0.936170 (900 4500);
PAINT GREEN (900 4500);
DISPLAY INVISIBLE (900 4500);
FORCEADD OFFPAGE..3
(1600 5150);
FORCEPROP 2 LAST $XR0 27 
J 0
(1814 5150);
DISPLAY 0.638298 (1814 5150);
PAINT MONO (1814 5150);
FORCEPROP 2 LAST $XR1 52 
J 0
(1904 5150);
DISPLAY 0.638298 (1904 5150);
PAINT MONO (1904 5150);
FORCEPROP 2 LAST CDS_LIB mstr_standard
J 0
(1600 5150);
DISPLAY 0.787234 (1600 5150);
PAINT MONO (1600 5150);
DISPLAY INVISIBLE (1600 5150);
FORCEPROP 1 LAST OFFPAGE TRUE
J 0
(1925 5025);
DISPLAY 0.936170 (1925 5025);
PAINT GREEN (1925 5025);
DISPLAY INVISIBLE (1925 5025);
FORCEPROP 1 LAST COMMENT_BODY TRUE
J 0
(1550 5050);
DISPLAY 0.936170 (1550 5050);
PAINT GREEN (1550 5050);
DISPLAY INVISIBLE (1550 5050);
FORCEPROP 2 LAST PATH I2
J 0
(1800 5225);
DISPLAY 0.787234 (1800 5225);
PAINT MONO (1800 5225);
DISPLAY INVISIBLE (1800 5225);
FORCEADD TAP..6
R 2
(900 4400);
FORCEPROP 3 LASTPIN (850 4400) SIG_NAME M_E_DQS_DN<10>
J 0
(860 4410);
DISPLAY 0.659574 (860 4410);
PAINT MONO (860 4410);
DISPLAY INVISIBLE (860 4410);
FORCEPROP 1 LASTPIN (850 4400) BN 10
J 2
(900 4410);
DISPLAY 0.617021 (900 4410);
PAINT PINK (900 4410);
FORCEPROP 2 LAST CDS_LIB mstr_standard
J 0
(900 4400);
DISPLAY 0.787234 (900 4400);
PAINT MONO (900 4400);
DISPLAY INVISIBLE (900 4400);
FORCEPROP 1 LAST BODY_TYPE PLUMBING
J 2
(900 4350);
DISPLAY 1.234043 (900 4350);
PAINT GREEN (900 4350);
DISPLAY INVISIBLE (900 4350);
FORCEPROP 1 LAST HDL_TAP TRUE
J 2
(575 4275);
DISPLAY 1.234043 (575 4275);
PAINT GREEN (575 4275);
DISPLAY INVISIBLE (575 4275);
FORCEPROP 1 LAST PATH I20
J 2
(900 4400);
DISPLAY 0.936170 (900 4400);
PAINT GREEN (900 4400);
DISPLAY INVISIBLE (900 4400);
FORCEADD TAP..6
R 2
(900 4300);
FORCEPROP 3 LASTPIN (850 4300) SIG_NAME M_E_DQS_DN<9>
J 0
(860 4310);
DISPLAY 0.659574 (860 4310);
PAINT MONO (860 4310);
DISPLAY INVISIBLE (860 4310);
FORCEPROP 1 LASTPIN (850 4300) BN 9
J 2
(900 4310);
DISPLAY 0.617021 (900 4310);
PAINT PINK (900 4310);
FORCEPROP 2 LAST CDS_LIB mstr_standard
J 0
(900 4300);
DISPLAY 0.787234 (900 4300);
PAINT MONO (900 4300);
DISPLAY INVISIBLE (900 4300);
FORCEPROP 1 LAST BODY_TYPE PLUMBING
J 2
(900 4250);
DISPLAY 1.234043 (900 4250);
PAINT GREEN (900 4250);
DISPLAY INVISIBLE (900 4250);
FORCEPROP 1 LAST HDL_TAP TRUE
J 2
(575 4175);
DISPLAY 1.234043 (575 4175);
PAINT GREEN (575 4175);
DISPLAY INVISIBLE (575 4175);
FORCEPROP 1 LAST PATH I21
J 2
(900 4300);
DISPLAY 0.936170 (900 4300);
PAINT GREEN (900 4300);
DISPLAY INVISIBLE (900 4300);
FORCEADD TAP..6
R 2
(900 4200);
FORCEPROP 3 LASTPIN (850 4200) SIG_NAME M_E_DQS_DN<8>
J 0
(860 4210);
DISPLAY 0.659574 (860 4210);
PAINT MONO (860 4210);
DISPLAY INVISIBLE (860 4210);
FORCEPROP 1 LASTPIN (850 4200) BN 8
J 2
(900 4210);
DISPLAY 0.617021 (900 4210);
PAINT PINK (900 4210);
FORCEPROP 2 LAST CDS_LIB mstr_standard
J 0
(900 4200);
DISPLAY 0.787234 (900 4200);
PAINT MONO (900 4200);
DISPLAY INVISIBLE (900 4200);
FORCEPROP 1 LAST BODY_TYPE PLUMBING
J 2
(900 4150);
DISPLAY 1.234043 (900 4150);
PAINT GREEN (900 4150);
DISPLAY INVISIBLE (900 4150);
FORCEPROP 1 LAST HDL_TAP TRUE
J 2
(575 4075);
DISPLAY 1.234043 (575 4075);
PAINT GREEN (575 4075);
DISPLAY INVISIBLE (575 4075);
FORCEPROP 1 LAST PATH I22
J 2
(900 4200);
DISPLAY 0.936170 (900 4200);
PAINT GREEN (900 4200);
DISPLAY INVISIBLE (900 4200);
FORCEADD TAP..6
R 2
(900 4100);
FORCEPROP 3 LASTPIN (850 4100) SIG_NAME M_E_DQS_DN<7>
J 0
(860 4110);
DISPLAY 0.659574 (860 4110);
PAINT MONO (860 4110);
DISPLAY INVISIBLE (860 4110);
FORCEPROP 1 LASTPIN (850 4100) BN 7
J 2
(900 4110);
DISPLAY 0.617021 (900 4110);
PAINT PINK (900 4110);
FORCEPROP 2 LAST CDS_LIB mstr_standard
J 0
(900 4100);
DISPLAY 0.787234 (900 4100);
PAINT MONO (900 4100);
DISPLAY INVISIBLE (900 4100);
FORCEPROP 1 LAST BODY_TYPE PLUMBING
J 2
(900 4050);
DISPLAY 1.234043 (900 4050);
PAINT GREEN (900 4050);
DISPLAY INVISIBLE (900 4050);
FORCEPROP 1 LAST HDL_TAP TRUE
J 2
(575 3975);
DISPLAY 1.234043 (575 3975);
PAINT GREEN (575 3975);
DISPLAY INVISIBLE (575 3975);
FORCEPROP 1 LAST PATH I23
J 2
(900 4100);
DISPLAY 0.936170 (900 4100);
PAINT GREEN (900 4100);
DISPLAY INVISIBLE (900 4100);
FORCEADD TAP..6
R 2
(700 4350);
FORCEPROP 3 LASTPIN (650 4350) SIG_NAME M_E_DQS_DP<9>
J 0
(660 4360);
DISPLAY 0.659574 (660 4360);
PAINT MONO (660 4360);
DISPLAY INVISIBLE (660 4360);
FORCEPROP 1 LASTPIN (650 4350) BN 9
J 2
(700 4360);
DISPLAY 0.617021 (700 4360);
PAINT PINK (700 4360);
FORCEPROP 2 LAST CDS_LIB mstr_standard
J 0
(700 4350);
DISPLAY 0.787234 (700 4350);
PAINT MONO (700 4350);
DISPLAY INVISIBLE (700 4350);
FORCEPROP 1 LAST BODY_TYPE PLUMBING
J 2
(700 4300);
DISPLAY 1.234043 (700 4300);
PAINT GREEN (700 4300);
DISPLAY INVISIBLE (700 4300);
FORCEPROP 1 LAST HDL_TAP TRUE
J 2
(375 4225);
DISPLAY 1.234043 (375 4225);
PAINT GREEN (375 4225);
DISPLAY INVISIBLE (375 4225);
FORCEPROP 1 LAST PATH I24
J 2
(700 4350);
DISPLAY 0.936170 (700 4350);
PAINT GREEN (700 4350);
DISPLAY INVISIBLE (700 4350);
FORCEADD TAP..6
R 2
(700 4450);
FORCEPROP 3 LASTPIN (650 4450) SIG_NAME M_E_DQS_DP<10>
J 0
(660 4460);
DISPLAY 0.659574 (660 4460);
PAINT MONO (660 4460);
DISPLAY INVISIBLE (660 4460);
FORCEPROP 1 LASTPIN (650 4450) BN 10
J 2
(700 4460);
DISPLAY 0.617021 (700 4460);
PAINT PINK (700 4460);
FORCEPROP 2 LAST CDS_LIB mstr_standard
J 0
(700 4450);
DISPLAY 0.787234 (700 4450);
PAINT MONO (700 4450);
DISPLAY INVISIBLE (700 4450);
FORCEPROP 1 LAST BODY_TYPE PLUMBING
J 2
(700 4400);
DISPLAY 1.234043 (700 4400);
PAINT GREEN (700 4400);
DISPLAY INVISIBLE (700 4400);
FORCEPROP 1 LAST HDL_TAP TRUE
J 2
(375 4325);
DISPLAY 1.234043 (375 4325);
PAINT GREEN (375 4325);
DISPLAY INVISIBLE (375 4325);
FORCEPROP 1 LAST PATH I25
J 2
(700 4450);
DISPLAY 0.936170 (700 4450);
PAINT GREEN (700 4450);
DISPLAY INVISIBLE (700 4450);
FORCEADD TAP..6
R 2
(700 4250);
FORCEPROP 3 LASTPIN (650 4250) SIG_NAME M_E_DQS_DP<8>
J 0
(660 4260);
DISPLAY 0.659574 (660 4260);
PAINT MONO (660 4260);
DISPLAY INVISIBLE (660 4260);
FORCEPROP 1 LASTPIN (650 4250) BN 8
J 2
(700 4260);
DISPLAY 0.617021 (700 4260);
PAINT PINK (700 4260);
FORCEPROP 2 LAST CDS_LIB mstr_standard
J 0
(700 4250);
DISPLAY 0.787234 (700 4250);
PAINT MONO (700 4250);
DISPLAY INVISIBLE (700 4250);
FORCEPROP 1 LAST BODY_TYPE PLUMBING
J 2
(700 4200);
DISPLAY 1.234043 (700 4200);
PAINT GREEN (700 4200);
DISPLAY INVISIBLE (700 4200);
FORCEPROP 1 LAST HDL_TAP TRUE
J 2
(375 4125);
DISPLAY 1.234043 (375 4125);
PAINT GREEN (375 4125);
DISPLAY INVISIBLE (375 4125);
FORCEPROP 1 LAST PATH I26
J 2
(700 4250);
DISPLAY 0.936170 (700 4250);
PAINT GREEN (700 4250);
DISPLAY INVISIBLE (700 4250);
FORCEADD TAP..6
R 2
(700 4050);
FORCEPROP 3 LASTPIN (650 4050) SIG_NAME M_E_DQS_DP<6>
J 0
(660 4060);
DISPLAY 0.659574 (660 4060);
PAINT MONO (660 4060);
DISPLAY INVISIBLE (660 4060);
FORCEPROP 1 LASTPIN (650 4050) BN 6
J 2
(700 4060);
DISPLAY 0.617021 (700 4060);
PAINT PINK (700 4060);
FORCEPROP 2 LAST CDS_LIB mstr_standard
J 0
(700 4050);
DISPLAY 0.787234 (700 4050);
PAINT MONO (700 4050);
DISPLAY INVISIBLE (700 4050);
FORCEPROP 1 LAST BODY_TYPE PLUMBING
J 2
(700 4000);
DISPLAY 1.234043 (700 4000);
PAINT GREEN (700 4000);
DISPLAY INVISIBLE (700 4000);
FORCEPROP 1 LAST HDL_TAP TRUE
J 2
(375 3925);
DISPLAY 1.234043 (375 3925);
PAINT GREEN (375 3925);
DISPLAY INVISIBLE (375 3925);
FORCEPROP 1 LAST PATH I27
J 2
(700 4050);
DISPLAY 0.936170 (700 4050);
PAINT GREEN (700 4050);
DISPLAY INVISIBLE (700 4050);
FORCEADD TAP..6
R 2
(700 4150);
FORCEPROP 3 LASTPIN (650 4150) SIG_NAME M_E_DQS_DP<7>
J 0
(660 4160);
DISPLAY 0.659574 (660 4160);
PAINT MONO (660 4160);
DISPLAY INVISIBLE (660 4160);
FORCEPROP 1 LASTPIN (650 4150) BN 7
J 2
(700 4160);
DISPLAY 0.617021 (700 4160);
PAINT PINK (700 4160);
FORCEPROP 2 LAST CDS_LIB mstr_standard
J 0
(700 4150);
DISPLAY 0.787234 (700 4150);
PAINT MONO (700 4150);
DISPLAY INVISIBLE (700 4150);
FORCEPROP 1 LAST BODY_TYPE PLUMBING
J 2
(700 4100);
DISPLAY 1.234043 (700 4100);
PAINT GREEN (700 4100);
DISPLAY INVISIBLE (700 4100);
FORCEPROP 1 LAST HDL_TAP TRUE
J 2
(375 4025);
DISPLAY 1.234043 (375 4025);
PAINT GREEN (375 4025);
DISPLAY INVISIBLE (375 4025);
FORCEPROP 1 LAST PATH I28
J 2
(700 4150);
DISPLAY 0.936170 (700 4150);
PAINT GREEN (700 4150);
DISPLAY INVISIBLE (700 4150);
FORCEADD TAP..6
R 2
(900 4000);
FORCEPROP 3 LASTPIN (850 4000) SIG_NAME M_E_DQS_DN<6>
J 0
(860 4010);
DISPLAY 0.659574 (860 4010);
PAINT MONO (860 4010);
DISPLAY INVISIBLE (860 4010);
FORCEPROP 1 LASTPIN (850 4000) BN 6
J 2
(900 4010);
DISPLAY 0.617021 (900 4010);
PAINT PINK (900 4010);
FORCEPROP 2 LAST CDS_LIB mstr_standard
J 0
(900 4000);
DISPLAY 0.787234 (900 4000);
PAINT MONO (900 4000);
DISPLAY INVISIBLE (900 4000);
FORCEPROP 1 LAST BODY_TYPE PLUMBING
J 2
(900 3950);
DISPLAY 1.234043 (900 3950);
PAINT GREEN (900 3950);
DISPLAY INVISIBLE (900 3950);
FORCEPROP 1 LAST HDL_TAP TRUE
J 2
(575 3875);
DISPLAY 1.234043 (575 3875);
PAINT GREEN (575 3875);
DISPLAY INVISIBLE (575 3875);
FORCEPROP 1 LAST PATH I29
J 2
(900 4000);
DISPLAY 0.936170 (900 4000);
PAINT GREEN (900 4000);
DISPLAY INVISIBLE (900 4000);
FORCEADD TAP..6
R 2
(900 5100);
FORCEPROP 3 LASTPIN (850 5100) SIG_NAME M_E_DQS_DN<17>
J 0
(860 5110);
DISPLAY 0.659574 (860 5110);
PAINT MONO (860 5110);
DISPLAY INVISIBLE (860 5110);
FORCEPROP 1 LASTPIN (850 5100) BN 17
J 2
(900 5110);
DISPLAY 0.617021 (900 5110);
PAINT PINK (900 5110);
FORCEPROP 2 LAST CDS_LIB mstr_standard
J 2
(900 5100);
DISPLAY 0.787234 (900 5100);
PAINT MONO (900 5100);
DISPLAY INVISIBLE (900 5100);
FORCEPROP 1 LAST BODY_TYPE PLUMBING
J 2
(900 5050);
DISPLAY 1.234043 (900 5050);
PAINT GREEN (900 5050);
DISPLAY INVISIBLE (900 5050);
FORCEPROP 1 LAST HDL_TAP TRUE
J 2
(575 4975);
DISPLAY 1.234043 (575 4975);
PAINT GREEN (575 4975);
DISPLAY INVISIBLE (575 4975);
FORCEPROP 1 LAST PATH I3
J 2
(900 5100);
DISPLAY 0.936170 (900 5100);
PAINT GREEN (900 5100);
DISPLAY INVISIBLE (900 5100);
FORCEADD TAP..6
R 2
(900 3900);
FORCEPROP 3 LASTPIN (850 3900) SIG_NAME M_E_DQS_DN<5>
J 0
(860 3910);
DISPLAY 0.659574 (860 3910);
PAINT MONO (860 3910);
DISPLAY INVISIBLE (860 3910);
FORCEPROP 1 LASTPIN (850 3900) BN 5
J 2
(900 3910);
DISPLAY 0.617021 (900 3910);
PAINT PINK (900 3910);
FORCEPROP 2 LAST CDS_LIB mstr_standard
J 0
(900 3900);
DISPLAY 0.787234 (900 3900);
PAINT MONO (900 3900);
DISPLAY INVISIBLE (900 3900);
FORCEPROP 1 LAST BODY_TYPE PLUMBING
J 2
(900 3850);
DISPLAY 1.234043 (900 3850);
PAINT GREEN (900 3850);
DISPLAY INVISIBLE (900 3850);
FORCEPROP 1 LAST HDL_TAP TRUE
J 2
(575 3775);
DISPLAY 1.234043 (575 3775);
PAINT GREEN (575 3775);
DISPLAY INVISIBLE (575 3775);
FORCEPROP 1 LAST PATH I30
J 2
(900 3900);
DISPLAY 0.936170 (900 3900);
PAINT GREEN (900 3900);
DISPLAY INVISIBLE (900 3900);
FORCEADD TAP..6
R 2
(900 3800);
FORCEPROP 3 LASTPIN (850 3800) SIG_NAME M_E_DQS_DN<4>
J 0
(860 3810);
DISPLAY 0.659574 (860 3810);
PAINT MONO (860 3810);
DISPLAY INVISIBLE (860 3810);
FORCEPROP 1 LASTPIN (850 3800) BN 4
J 2
(900 3810);
DISPLAY 0.617021 (900 3810);
PAINT PINK (900 3810);
FORCEPROP 2 LAST CDS_LIB mstr_standard
J 0
(900 3800);
DISPLAY 0.787234 (900 3800);
PAINT MONO (900 3800);
DISPLAY INVISIBLE (900 3800);
FORCEPROP 1 LAST BODY_TYPE PLUMBING
J 2
(900 3750);
DISPLAY 1.234043 (900 3750);
PAINT GREEN (900 3750);
DISPLAY INVISIBLE (900 3750);
FORCEPROP 1 LAST HDL_TAP TRUE
J 2
(575 3675);
DISPLAY 1.234043 (575 3675);
PAINT GREEN (575 3675);
DISPLAY INVISIBLE (575 3675);
FORCEPROP 1 LAST PATH I31
J 2
(900 3800);
DISPLAY 0.936170 (900 3800);
PAINT GREEN (900 3800);
DISPLAY INVISIBLE (900 3800);
FORCEADD TAP..6
R 2
(900 3700);
FORCEPROP 3 LASTPIN (850 3700) SIG_NAME M_E_DQS_DN<3>
J 0
(860 3710);
DISPLAY 0.659574 (860 3710);
PAINT MONO (860 3710);
DISPLAY INVISIBLE (860 3710);
FORCEPROP 1 LASTPIN (850 3700) BN 3
J 2
(900 3710);
DISPLAY 0.617021 (900 3710);
PAINT PINK (900 3710);
FORCEPROP 2 LAST CDS_LIB mstr_standard
J 0
(900 3700);
DISPLAY 0.787234 (900 3700);
PAINT MONO (900 3700);
DISPLAY INVISIBLE (900 3700);
FORCEPROP 1 LAST BODY_TYPE PLUMBING
J 2
(900 3650);
DISPLAY 1.234043 (900 3650);
PAINT GREEN (900 3650);
DISPLAY INVISIBLE (900 3650);
FORCEPROP 1 LAST HDL_TAP TRUE
J 2
(575 3575);
DISPLAY 1.234043 (575 3575);
PAINT GREEN (575 3575);
DISPLAY INVISIBLE (575 3575);
FORCEPROP 1 LAST PATH I32
J 2
(900 3700);
DISPLAY 0.936170 (900 3700);
PAINT GREEN (900 3700);
DISPLAY INVISIBLE (900 3700);
FORCEADD TAP..6
R 2
(900 3600);
FORCEPROP 3 LASTPIN (850 3600) SIG_NAME M_E_DQS_DN<2>
J 0
(860 3610);
DISPLAY 0.659574 (860 3610);
PAINT MONO (860 3610);
DISPLAY INVISIBLE (860 3610);
FORCEPROP 1 LASTPIN (850 3600) BN 2
J 2
(900 3610);
DISPLAY 0.617021 (900 3610);
PAINT PINK (900 3610);
FORCEPROP 2 LAST CDS_LIB mstr_standard
J 0
(900 3600);
DISPLAY 0.787234 (900 3600);
PAINT MONO (900 3600);
DISPLAY INVISIBLE (900 3600);
FORCEPROP 1 LAST BODY_TYPE PLUMBING
J 2
(900 3550);
DISPLAY 1.234043 (900 3550);
PAINT GREEN (900 3550);
DISPLAY INVISIBLE (900 3550);
FORCEPROP 1 LAST HDL_TAP TRUE
J 2
(575 3475);
DISPLAY 1.234043 (575 3475);
PAINT GREEN (575 3475);
DISPLAY INVISIBLE (575 3475);
FORCEPROP 1 LAST PATH I33
J 2
(900 3600);
DISPLAY 0.936170 (900 3600);
PAINT GREEN (900 3600);
DISPLAY INVISIBLE (900 3600);
FORCEADD TAP..6
R 2
(700 3850);
FORCEPROP 3 LASTPIN (650 3850) SIG_NAME M_E_DQS_DP<4>
J 0
(660 3860);
DISPLAY 0.659574 (660 3860);
PAINT MONO (660 3860);
DISPLAY INVISIBLE (660 3860);
FORCEPROP 1 LASTPIN (650 3850) BN 4
J 2
(700 3860);
DISPLAY 0.617021 (700 3860);
PAINT PINK (700 3860);
FORCEPROP 2 LAST CDS_LIB mstr_standard
J 0
(700 3850);
DISPLAY 0.787234 (700 3850);
PAINT MONO (700 3850);
DISPLAY INVISIBLE (700 3850);
FORCEPROP 1 LAST BODY_TYPE PLUMBING
J 2
(700 3800);
DISPLAY 1.234043 (700 3800);
PAINT GREEN (700 3800);
DISPLAY INVISIBLE (700 3800);
FORCEPROP 1 LAST HDL_TAP TRUE
J 2
(375 3725);
DISPLAY 1.234043 (375 3725);
PAINT GREEN (375 3725);
DISPLAY INVISIBLE (375 3725);
FORCEPROP 1 LAST PATH I34
J 2
(700 3850);
DISPLAY 0.936170 (700 3850);
PAINT GREEN (700 3850);
DISPLAY INVISIBLE (700 3850);
FORCEADD TAP..6
R 2
(700 3950);
FORCEPROP 3 LASTPIN (650 3950) SIG_NAME M_E_DQS_DP<5>
J 0
(660 3960);
DISPLAY 0.659574 (660 3960);
PAINT MONO (660 3960);
DISPLAY INVISIBLE (660 3960);
FORCEPROP 1 LASTPIN (650 3950) BN 5
J 2
(700 3960);
DISPLAY 0.617021 (700 3960);
PAINT PINK (700 3960);
FORCEPROP 2 LAST CDS_LIB mstr_standard
J 0
(700 3950);
DISPLAY 0.787234 (700 3950);
PAINT MONO (700 3950);
DISPLAY INVISIBLE (700 3950);
FORCEPROP 1 LAST BODY_TYPE PLUMBING
J 2
(700 3900);
DISPLAY 1.234043 (700 3900);
PAINT GREEN (700 3900);
DISPLAY INVISIBLE (700 3900);
FORCEPROP 1 LAST HDL_TAP TRUE
J 2
(375 3825);
DISPLAY 1.234043 (375 3825);
PAINT GREEN (375 3825);
DISPLAY INVISIBLE (375 3825);
FORCEPROP 1 LAST PATH I35
J 2
(700 3950);
DISPLAY 0.936170 (700 3950);
PAINT GREEN (700 3950);
DISPLAY INVISIBLE (700 3950);
FORCEADD TAP..6
R 2
(700 3750);
FORCEPROP 3 LASTPIN (650 3750) SIG_NAME M_E_DQS_DP<3>
J 0
(660 3760);
DISPLAY 0.659574 (660 3760);
PAINT MONO (660 3760);
DISPLAY INVISIBLE (660 3760);
FORCEPROP 1 LASTPIN (650 3750) BN 3
J 2
(700 3760);
DISPLAY 0.617021 (700 3760);
PAINT PINK (700 3760);
FORCEPROP 2 LAST CDS_LIB mstr_standard
J 0
(700 3750);
DISPLAY 0.787234 (700 3750);
PAINT MONO (700 3750);
DISPLAY INVISIBLE (700 3750);
FORCEPROP 1 LAST BODY_TYPE PLUMBING
J 2
(700 3700);
DISPLAY 1.234043 (700 3700);
PAINT GREEN (700 3700);
DISPLAY INVISIBLE (700 3700);
FORCEPROP 1 LAST HDL_TAP TRUE
J 2
(375 3625);
DISPLAY 1.234043 (375 3625);
PAINT GREEN (375 3625);
DISPLAY INVISIBLE (375 3625);
FORCEPROP 1 LAST PATH I36
J 2
(700 3750);
DISPLAY 0.936170 (700 3750);
PAINT GREEN (700 3750);
DISPLAY INVISIBLE (700 3750);
FORCEADD TAP..6
R 2
(700 3650);
FORCEPROP 3 LASTPIN (650 3650) SIG_NAME M_E_DQS_DP<2>
J 0
(660 3660);
DISPLAY 0.659574 (660 3660);
PAINT MONO (660 3660);
DISPLAY INVISIBLE (660 3660);
FORCEPROP 1 LASTPIN (650 3650) BN 2
J 2
(700 3660);
DISPLAY 0.617021 (700 3660);
PAINT PINK (700 3660);
FORCEPROP 2 LAST CDS_LIB mstr_standard
J 0
(700 3650);
DISPLAY 0.787234 (700 3650);
PAINT MONO (700 3650);
DISPLAY INVISIBLE (700 3650);
FORCEPROP 1 LAST BODY_TYPE PLUMBING
J 2
(700 3600);
DISPLAY 1.234043 (700 3600);
PAINT GREEN (700 3600);
DISPLAY INVISIBLE (700 3600);
FORCEPROP 1 LAST HDL_TAP TRUE
J 2
(375 3525);
DISPLAY 1.234043 (375 3525);
PAINT GREEN (375 3525);
DISPLAY INVISIBLE (375 3525);
FORCEPROP 1 LAST PATH I37
J 2
(700 3650);
DISPLAY 0.936170 (700 3650);
PAINT GREEN (700 3650);
DISPLAY INVISIBLE (700 3650);
FORCEADD TAP..6
R 2
(700 3550);
FORCEPROP 3 LASTPIN (650 3550) SIG_NAME M_E_DQS_DP<1>
J 0
(660 3560);
DISPLAY 0.659574 (660 3560);
PAINT MONO (660 3560);
DISPLAY INVISIBLE (660 3560);
FORCEPROP 1 LASTPIN (650 3550) BN 1
J 2
(700 3560);
DISPLAY 0.617021 (700 3560);
PAINT PINK (700 3560);
FORCEPROP 2 LAST CDS_LIB mstr_standard
J 0
(700 3550);
DISPLAY 0.787234 (700 3550);
PAINT MONO (700 3550);
DISPLAY INVISIBLE (700 3550);
FORCEPROP 1 LAST BODY_TYPE PLUMBING
J 2
(700 3500);
DISPLAY 1.234043 (700 3500);
PAINT GREEN (700 3500);
DISPLAY INVISIBLE (700 3500);
FORCEPROP 1 LAST HDL_TAP TRUE
J 2
(375 3425);
DISPLAY 1.234043 (375 3425);
PAINT GREEN (375 3425);
DISPLAY INVISIBLE (375 3425);
FORCEPROP 1 LAST PATH I38
J 2
(700 3550);
DISPLAY 0.936170 (700 3550);
PAINT GREEN (700 3550);
DISPLAY INVISIBLE (700 3550);
FORCEADD TAP..6
R 2
(900 3400);
FORCEPROP 3 LASTPIN (850 3400) SIG_NAME M_E_DQS_DN<0>
J 0
(860 3410);
DISPLAY 0.659574 (860 3410);
PAINT MONO (860 3410);
DISPLAY INVISIBLE (860 3410);
FORCEPROP 1 LASTPIN (850 3400) BN 0
J 2
(900 3410);
DISPLAY 0.617021 (900 3410);
PAINT PINK (900 3410);
FORCEPROP 2 LAST CDS_LIB mstr_standard
J 0
(900 3400);
DISPLAY 0.787234 (900 3400);
PAINT MONO (900 3400);
DISPLAY INVISIBLE (900 3400);
FORCEPROP 1 LAST BODY_TYPE PLUMBING
J 2
(900 3350);
DISPLAY 1.234043 (900 3350);
PAINT GREEN (900 3350);
DISPLAY INVISIBLE (900 3350);
FORCEPROP 1 LAST HDL_TAP TRUE
J 2
(575 3275);
DISPLAY 1.234043 (575 3275);
PAINT GREEN (575 3275);
DISPLAY INVISIBLE (575 3275);
FORCEPROP 1 LAST PATH I39
J 2
(900 3400);
DISPLAY 0.936170 (900 3400);
PAINT GREEN (900 3400);
DISPLAY INVISIBLE (900 3400);
FORCEADD TAP..6
R 2
(700 5150);
FORCEPROP 3 LASTPIN (650 5150) SIG_NAME M_E_DQS_DP<17>
J 0
(660 5160);
DISPLAY 0.659574 (660 5160);
PAINT MONO (660 5160);
DISPLAY INVISIBLE (660 5160);
FORCEPROP 1 LASTPIN (650 5150) BN 17
J 2
(700 5160);
DISPLAY 0.617021 (700 5160);
PAINT PINK (700 5160);
FORCEPROP 2 LAST CDS_LIB mstr_standard
J 2
(700 5150);
DISPLAY 0.787234 (700 5150);
PAINT MONO (700 5150);
DISPLAY INVISIBLE (700 5150);
FORCEPROP 1 LAST BODY_TYPE PLUMBING
J 2
(700 5100);
DISPLAY 1.234043 (700 5100);
PAINT GREEN (700 5100);
DISPLAY INVISIBLE (700 5100);
FORCEPROP 1 LAST HDL_TAP TRUE
J 2
(375 5025);
DISPLAY 1.234043 (375 5025);
PAINT GREEN (375 5025);
DISPLAY INVISIBLE (375 5025);
FORCEPROP 1 LAST PATH I4
J 2
(700 5150);
DISPLAY 0.936170 (700 5150);
PAINT GREEN (700 5150);
DISPLAY INVISIBLE (700 5150);
FORCEADD TAP..6
R 2
(900 3500);
FORCEPROP 3 LASTPIN (850 3500) SIG_NAME M_E_DQS_DN<1>
J 0
(860 3510);
DISPLAY 0.659574 (860 3510);
PAINT MONO (860 3510);
DISPLAY INVISIBLE (860 3510);
FORCEPROP 1 LASTPIN (850 3500) BN 1
J 2
(900 3510);
DISPLAY 0.617021 (900 3510);
PAINT PINK (900 3510);
FORCEPROP 2 LAST CDS_LIB mstr_standard
J 0
(900 3500);
DISPLAY 0.787234 (900 3500);
PAINT MONO (900 3500);
DISPLAY INVISIBLE (900 3500);
FORCEPROP 1 LAST BODY_TYPE PLUMBING
J 2
(900 3450);
DISPLAY 1.234043 (900 3450);
PAINT GREEN (900 3450);
DISPLAY INVISIBLE (900 3450);
FORCEPROP 1 LAST HDL_TAP TRUE
J 2
(575 3375);
DISPLAY 1.234043 (575 3375);
PAINT GREEN (575 3375);
DISPLAY INVISIBLE (575 3375);
FORCEPROP 1 LAST PATH I40
J 2
(900 3500);
DISPLAY 0.936170 (900 3500);
PAINT GREEN (900 3500);
DISPLAY INVISIBLE (900 3500);
FORCEADD TAP..6
R 2
(700 3450);
FORCEPROP 3 LASTPIN (650 3450) SIG_NAME M_E_DQS_DP<0>
J 0
(660 3460);
DISPLAY 0.659574 (660 3460);
PAINT MONO (660 3460);
DISPLAY INVISIBLE (660 3460);
FORCEPROP 1 LASTPIN (650 3450) BN 0
J 2
(700 3460);
DISPLAY 0.617021 (700 3460);
PAINT PINK (700 3460);
FORCEPROP 2 LAST CDS_LIB mstr_standard
J 0
(700 3450);
DISPLAY 0.787234 (700 3450);
PAINT MONO (700 3450);
DISPLAY INVISIBLE (700 3450);
FORCEPROP 1 LAST BODY_TYPE PLUMBING
J 2
(700 3400);
DISPLAY 1.234043 (700 3400);
PAINT GREEN (700 3400);
DISPLAY INVISIBLE (700 3400);
FORCEPROP 1 LAST HDL_TAP TRUE
J 2
(375 3325);
DISPLAY 1.234043 (375 3325);
PAINT GREEN (375 3325);
DISPLAY INVISIBLE (375 3325);
FORCEPROP 1 LAST PATH I41
J 2
(700 3450);
DISPLAY 0.936170 (700 3450);
PAINT GREEN (700 3450);
DISPLAY INVISIBLE (700 3450);
FORCEADD SCONN288_H44441004..3
(1800 2500);
FORCEPROP 1 LAST LOCATION J4A2
J 0
(1350 3900);
DISPLAY 0.617021 (1350 3900);
PAINT AQUA (1350 3900);
FORCEPROP 1 LAST PART_NUMBER H44441-004
J 0
(1350 1150);
DISPLAY 0.617021 (1350 1150);
PAINT BLUE (1350 1150);
FORCEPROP 1 LAST MATERIAL SCONN
J 0
(1350 3850);
DISPLAY 0.617021 (1350 3850);
PAINT SKYBLUE (1350 3850);
FORCEPROP 2 LASTPIN (1300 3650) $PN 2
J 2
(1290 3660);
DISPLAY 0.617021 (1290 3660);
PAINT ORANGE (1290 3660);
FORCEPROP 2 LASTPIN (1300 3600) $PN 4
J 2
(1290 3610);
DISPLAY 0.617021 (1290 3610);
PAINT ORANGE (1290 3610);
FORCEPROP 2 LASTPIN (1300 3550) $PN 6
J 2
(1290 3560);
DISPLAY 0.617021 (1290 3560);
PAINT ORANGE (1290 3560);
FORCEPROP 2 LASTPIN (1300 3500) $PN 9
J 2
(1290 3510);
DISPLAY 0.617021 (1290 3510);
PAINT ORANGE (1290 3510);
FORCEPROP 2 LASTPIN (1300 3450) $PN 11
J 2
(1290 3460);
DISPLAY 0.617021 (1290 3460);
PAINT ORANGE (1290 3460);
FORCEPROP 2 LASTPIN (1300 3400) $PN 13
J 2
(1290 3410);
DISPLAY 0.617021 (1290 3410);
PAINT ORANGE (1290 3410);
FORCEPROP 2 LASTPIN (1300 3350) $PN 15
J 2
(1290 3360);
DISPLAY 0.617021 (1290 3360);
PAINT ORANGE (1290 3360);
FORCEPROP 2 LASTPIN (1300 3300) $PN 17
J 2
(1290 3310);
DISPLAY 0.617021 (1290 3310);
PAINT ORANGE (1290 3310);
FORCEPROP 2 LASTPIN (1300 3250) $PN 20
J 2
(1290 3260);
DISPLAY 0.617021 (1290 3260);
PAINT ORANGE (1290 3260);
FORCEPROP 2 LASTPIN (1300 3200) $PN 22
J 2
(1290 3210);
DISPLAY 0.617021 (1290 3210);
PAINT ORANGE (1290 3210);
FORCEPROP 2 LASTPIN (1300 3150) $PN 24
J 2
(1290 3160);
DISPLAY 0.617021 (1290 3160);
PAINT ORANGE (1290 3160);
FORCEPROP 2 LASTPIN (1300 3100) $PN 26
J 2
(1290 3110);
DISPLAY 0.617021 (1290 3110);
PAINT ORANGE (1290 3110);
FORCEPROP 2 LASTPIN (1300 3050) $PN 28
J 2
(1290 3060);
DISPLAY 0.617021 (1290 3060);
PAINT ORANGE (1290 3060);
FORCEPROP 2 LASTPIN (1300 3000) $PN 31
J 2
(1290 3010);
DISPLAY 0.617021 (1290 3010);
PAINT ORANGE (1290 3010);
FORCEPROP 2 LASTPIN (1300 2950) $PN 33
J 2
(1290 2960);
DISPLAY 0.617021 (1290 2960);
PAINT ORANGE (1290 2960);
FORCEPROP 2 LASTPIN (1300 2900) $PN 35
J 2
(1290 2910);
DISPLAY 0.617021 (1290 2910);
PAINT ORANGE (1290 2910);
FORCEPROP 2 LASTPIN (1300 2850) $PN 37
J 2
(1290 2860);
DISPLAY 0.617021 (1290 2860);
PAINT ORANGE (1290 2860);
FORCEPROP 2 LASTPIN (1300 2800) $PN 39
J 2
(1290 2810);
DISPLAY 0.617021 (1290 2810);
PAINT ORANGE (1290 2810);
FORCEPROP 2 LASTPIN (1300 2750) $PN 42
J 2
(1290 2760);
DISPLAY 0.617021 (1290 2760);
PAINT ORANGE (1290 2760);
FORCEPROP 2 LASTPIN (1300 2700) $PN 44
J 2
(1290 2710);
DISPLAY 0.617021 (1290 2710);
PAINT ORANGE (1290 2710);
FORCEPROP 2 LASTPIN (1300 2650) $PN 46
J 2
(1290 2660);
DISPLAY 0.617021 (1290 2660);
PAINT ORANGE (1290 2660);
FORCEPROP 2 LASTPIN (1300 2600) $PN 48
J 2
(1290 2610);
DISPLAY 0.617021 (1290 2610);
PAINT ORANGE (1290 2610);
FORCEPROP 2 LASTPIN (1300 2550) $PN 50
J 2
(1290 2560);
DISPLAY 0.617021 (1290 2560);
PAINT ORANGE (1290 2560);
FORCEPROP 2 LASTPIN (1300 2500) $PN 53
J 2
(1290 2510);
DISPLAY 0.617021 (1290 2510);
PAINT ORANGE (1290 2510);
FORCEPROP 2 LASTPIN (1300 2450) $PN 55
J 2
(1290 2460);
DISPLAY 0.617021 (1290 2460);
PAINT ORANGE (1290 2460);
FORCEPROP 2 LASTPIN (1300 2400) $PN 57
J 2
(1290 2410);
DISPLAY 0.617021 (1290 2410);
PAINT ORANGE (1290 2410);
FORCEPROP 2 LASTPIN (1300 2350) $PN 94
J 2
(1290 2360);
DISPLAY 0.617021 (1290 2360);
PAINT ORANGE (1290 2360);
FORCEPROP 2 LASTPIN (1300 2300) $PN 96
J 2
(1290 2310);
DISPLAY 0.617021 (1290 2310);
PAINT ORANGE (1290 2310);
FORCEPROP 2 LASTPIN (1300 2250) $PN 98
J 2
(1290 2260);
DISPLAY 0.617021 (1290 2260);
PAINT ORANGE (1290 2260);
FORCEPROP 2 LASTPIN (1300 2200) $PN 101
J 2
(1290 2210);
DISPLAY 0.617021 (1290 2210);
PAINT ORANGE (1290 2210);
FORCEPROP 2 LASTPIN (1300 2150) $PN 103
J 2
(1290 2160);
DISPLAY 0.617021 (1290 2160);
PAINT ORANGE (1290 2160);
FORCEPROP 2 LASTPIN (1300 2100) $PN 105
J 2
(1290 2110);
DISPLAY 0.617021 (1290 2110);
PAINT ORANGE (1290 2110);
FORCEPROP 2 LASTPIN (1300 2050) $PN 107
J 2
(1290 2060);
DISPLAY 0.617021 (1290 2060);
PAINT ORANGE (1290 2060);
FORCEPROP 2 LASTPIN (1300 2000) $PN 109
J 2
(1290 2010);
DISPLAY 0.617021 (1290 2010);
PAINT ORANGE (1290 2010);
FORCEPROP 2 LASTPIN (1300 1950) $PN 112
J 2
(1290 1960);
DISPLAY 0.617021 (1290 1960);
PAINT ORANGE (1290 1960);
FORCEPROP 2 LASTPIN (1300 1900) $PN 114
J 2
(1290 1910);
DISPLAY 0.617021 (1290 1910);
PAINT ORANGE (1290 1910);
FORCEPROP 2 LASTPIN (1300 1850) $PN 116
J 2
(1290 1860);
DISPLAY 0.617021 (1290 1860);
PAINT ORANGE (1290 1860);
FORCEPROP 2 LASTPIN (1300 1800) $PN 118
J 2
(1290 1810);
DISPLAY 0.617021 (1290 1810);
PAINT ORANGE (1290 1810);
FORCEPROP 2 LASTPIN (1300 1750) $PN 120
J 2
(1290 1760);
DISPLAY 0.617021 (1290 1760);
PAINT ORANGE (1290 1760);
FORCEPROP 2 LASTPIN (1300 1700) $PN 123
J 2
(1290 1710);
DISPLAY 0.617021 (1290 1710);
PAINT ORANGE (1290 1710);
FORCEPROP 2 LASTPIN (1300 1650) $PN 125
J 2
(1290 1660);
DISPLAY 0.617021 (1290 1660);
PAINT ORANGE (1290 1660);
FORCEPROP 2 LASTPIN (1300 1600) $PN 127
J 2
(1290 1610);
DISPLAY 0.617021 (1290 1610);
PAINT ORANGE (1290 1610);
FORCEPROP 2 LASTPIN (1300 1550) $PN 129
J 2
(1290 1560);
DISPLAY 0.617021 (1290 1560);
PAINT ORANGE (1290 1560);
FORCEPROP 2 LASTPIN (1300 1500) $PN 131
J 2
(1290 1510);
DISPLAY 0.617021 (1290 1510);
PAINT ORANGE (1290 1510);
FORCEPROP 2 LASTPIN (1300 1450) $PN 134
J 2
(1290 1460);
DISPLAY 0.617021 (1290 1460);
PAINT ORANGE (1290 1460);
FORCEPROP 2 LASTPIN (1300 1400) $PN 136
J 2
(1290 1410);
DISPLAY 0.617021 (1290 1410);
PAINT ORANGE (1290 1410);
FORCEPROP 2 LASTPIN (1300 1350) $PN 138
J 2
(1290 1360);
DISPLAY 0.617021 (1290 1360);
PAINT ORANGE (1290 1360);
FORCEPROP 2 LASTPIN (2300 3650) $PN 147
J 0
(2310 3660);
DISPLAY 0.617021 (2310 3660);
PAINT ORANGE (2310 3660);
FORCEPROP 2 LASTPIN (2300 3600) $PN 149
J 0
(2310 3610);
DISPLAY 0.617021 (2310 3610);
PAINT ORANGE (2310 3610);
FORCEPROP 2 LASTPIN (2300 3550) $PN 151
J 0
(2310 3560);
DISPLAY 0.617021 (2310 3560);
PAINT ORANGE (2310 3560);
FORCEPROP 2 LASTPIN (2300 3500) $PN 154
J 0
(2310 3510);
DISPLAY 0.617021 (2310 3510);
PAINT ORANGE (2310 3510);
FORCEPROP 2 LASTPIN (2300 3450) $PN 156
J 0
(2310 3460);
DISPLAY 0.617021 (2310 3460);
PAINT ORANGE (2310 3460);
FORCEPROP 2 LASTPIN (2300 3400) $PN 158
J 0
(2310 3410);
DISPLAY 0.617021 (2310 3410);
PAINT ORANGE (2310 3410);
FORCEPROP 2 LASTPIN (2300 3350) $PN 160
J 0
(2310 3360);
DISPLAY 0.617021 (2310 3360);
PAINT ORANGE (2310 3360);
FORCEPROP 2 LASTPIN (2300 3300) $PN 162
J 0
(2310 3310);
DISPLAY 0.617021 (2310 3310);
PAINT ORANGE (2310 3310);
FORCEPROP 2 LASTPIN (2300 3250) $PN 165
J 0
(2310 3260);
DISPLAY 0.617021 (2310 3260);
PAINT ORANGE (2310 3260);
FORCEPROP 2 LASTPIN (2300 3200) $PN 167
J 0
(2310 3210);
DISPLAY 0.617021 (2310 3210);
PAINT ORANGE (2310 3210);
FORCEPROP 2 LASTPIN (2300 3150) $PN 169
J 0
(2310 3160);
DISPLAY 0.617021 (2310 3160);
PAINT ORANGE (2310 3160);
FORCEPROP 2 LASTPIN (2300 3100) $PN 171
J 0
(2310 3110);
DISPLAY 0.617021 (2310 3110);
PAINT ORANGE (2310 3110);
FORCEPROP 2 LASTPIN (2300 3050) $PN 173
J 0
(2310 3060);
DISPLAY 0.617021 (2310 3060);
PAINT ORANGE (2310 3060);
FORCEPROP 2 LASTPIN (2300 3000) $PN 176
J 0
(2310 3010);
DISPLAY 0.617021 (2310 3010);
PAINT ORANGE (2310 3010);
FORCEPROP 2 LASTPIN (2300 2950) $PN 178
J 0
(2310 2960);
DISPLAY 0.617021 (2310 2960);
PAINT ORANGE (2310 2960);
FORCEPROP 2 LASTPIN (2300 2900) $PN 180
J 0
(2310 2910);
DISPLAY 0.617021 (2310 2910);
PAINT ORANGE (2310 2910);
FORCEPROP 2 LASTPIN (2300 2850) $PN 182
J 0
(2310 2860);
DISPLAY 0.617021 (2310 2860);
PAINT ORANGE (2310 2860);
FORCEPROP 2 LASTPIN (2300 2800) $PN 184
J 0
(2310 2810);
DISPLAY 0.617021 (2310 2810);
PAINT ORANGE (2310 2810);
FORCEPROP 2 LASTPIN (2300 2750) $PN 187
J 0
(2310 2760);
DISPLAY 0.617021 (2310 2760);
PAINT ORANGE (2310 2760);
FORCEPROP 2 LASTPIN (2300 2700) $PN 189
J 0
(2310 2710);
DISPLAY 0.617021 (2310 2710);
PAINT ORANGE (2310 2710);
FORCEPROP 2 LASTPIN (2300 2650) $PN 191
J 0
(2310 2660);
DISPLAY 0.617021 (2310 2660);
PAINT ORANGE (2310 2660);
FORCEPROP 2 LASTPIN (2300 2600) $PN 193
J 0
(2310 2610);
DISPLAY 0.617021 (2310 2610);
PAINT ORANGE (2310 2610);
FORCEPROP 2 LASTPIN (2300 2550) $PN 195
J 0
(2310 2560);
DISPLAY 0.617021 (2310 2560);
PAINT ORANGE (2310 2560);
FORCEPROP 2 LASTPIN (2300 2500) $PN 198
J 0
(2310 2510);
DISPLAY 0.617021 (2310 2510);
PAINT ORANGE (2310 2510);
FORCEPROP 2 LASTPIN (2300 2450) $PN 200
J 0
(2310 2460);
DISPLAY 0.617021 (2310 2460);
PAINT ORANGE (2310 2460);
FORCEPROP 2 LASTPIN (2300 2400) $PN 202
J 0
(2310 2410);
DISPLAY 0.617021 (2310 2410);
PAINT ORANGE (2310 2410);
FORCEPROP 2 LASTPIN (2300 2350) $PN 239
J 0
(2310 2360);
DISPLAY 0.617021 (2310 2360);
PAINT ORANGE (2310 2360);
FORCEPROP 2 LASTPIN (2300 2300) $PN 241
J 0
(2310 2310);
DISPLAY 0.617021 (2310 2310);
PAINT ORANGE (2310 2310);
FORCEPROP 2 LASTPIN (2300 2250) $PN 243
J 0
(2310 2260);
DISPLAY 0.617021 (2310 2260);
PAINT ORANGE (2310 2260);
FORCEPROP 2 LASTPIN (2300 2200) $PN 246
J 0
(2310 2210);
DISPLAY 0.617021 (2310 2210);
PAINT ORANGE (2310 2210);
FORCEPROP 2 LASTPIN (2300 2150) $PN 248
J 0
(2310 2160);
DISPLAY 0.617021 (2310 2160);
PAINT ORANGE (2310 2160);
FORCEPROP 2 LASTPIN (2300 2100) $PN 250
J 0
(2310 2110);
DISPLAY 0.617021 (2310 2110);
PAINT ORANGE (2310 2110);
FORCEPROP 2 LASTPIN (2300 2050) $PN 252
J 0
(2310 2060);
DISPLAY 0.617021 (2310 2060);
PAINT ORANGE (2310 2060);
FORCEPROP 2 LASTPIN (2300 2000) $PN 254
J 0
(2310 2010);
DISPLAY 0.617021 (2310 2010);
PAINT ORANGE (2310 2010);
FORCEPROP 2 LASTPIN (2300 1950) $PN 257
J 0
(2310 1960);
DISPLAY 0.617021 (2310 1960);
PAINT ORANGE (2310 1960);
FORCEPROP 2 LASTPIN (2300 1900) $PN 259
J 0
(2310 1910);
DISPLAY 0.617021 (2310 1910);
PAINT ORANGE (2310 1910);
FORCEPROP 2 LASTPIN (2300 1850) $PN 261
J 0
(2310 1860);
DISPLAY 0.617021 (2310 1860);
PAINT ORANGE (2310 1860);
FORCEPROP 2 LASTPIN (2300 1800) $PN 263
J 0
(2310 1810);
DISPLAY 0.617021 (2310 1810);
PAINT ORANGE (2310 1810);
FORCEPROP 2 LASTPIN (2300 1750) $PN 265
J 0
(2310 1760);
DISPLAY 0.617021 (2310 1760);
PAINT ORANGE (2310 1760);
FORCEPROP 2 LASTPIN (2300 1700) $PN 268
J 0
(2310 1710);
DISPLAY 0.617021 (2310 1710);
PAINT ORANGE (2310 1710);
FORCEPROP 2 LASTPIN (2300 1650) $PN 270
J 0
(2310 1660);
DISPLAY 0.617021 (2310 1660);
PAINT ORANGE (2310 1660);
FORCEPROP 2 LASTPIN (2300 1600) $PN 272
J 0
(2310 1610);
DISPLAY 0.617021 (2310 1610);
PAINT ORANGE (2310 1610);
FORCEPROP 2 LASTPIN (2300 1550) $PN 274
J 0
(2310 1560);
DISPLAY 0.617021 (2310 1560);
PAINT ORANGE (2310 1560);
FORCEPROP 2 LASTPIN (2300 1500) $PN 276
J 0
(2310 1510);
DISPLAY 0.617021 (2310 1510);
PAINT ORANGE (2310 1510);
FORCEPROP 2 LASTPIN (2300 1450) $PN 279
J 0
(2310 1460);
DISPLAY 0.617021 (2310 1460);
PAINT ORANGE (2310 1460);
FORCEPROP 2 LASTPIN (2300 1400) $PN 281
J 0
(2310 1410);
DISPLAY 0.617021 (2310 1410);
PAINT ORANGE (2310 1410);
FORCEPROP 2 LASTPIN (2300 1350) $PN 283
J 0
(2310 1360);
DISPLAY 0.617021 (2310 1360);
PAINT ORANGE (2310 1360);
FORCEPROP 1 LAST PACK_TYPE PIP
J 0
(1350 3950);
PAINT SKYBLUE (1350 3950);
DISPLAY INVISIBLE (1350 3950);
FORCEPROP 2 LAST BOM_COST MEM
J 0
(1800 2500);
PAINT ORANGE (1800 2500);
DISPLAY INVISIBLE (1800 2500);
FORCEPROP 2 LAST CDS_LIB mstr_sconn
J 0
(1800 2500);
PAINT ORANGE (1800 2500);
DISPLAY INVISIBLE (1800 2500);
FORCEPROP 2 LAST SEC_TYPE PIP
J 0
(1350 3950);
DISPLAY 1.021277 (1350 3950);
PAINT ORANGE (1350 3950);
DISPLAY INVISIBLE (1350 3950);
FORCEPROP 2 LAST SEC 3
J 0
(1350 3950);
DISPLAY 0.680851 (1350 3950);
PAINT MONO (1350 3950);
DISPLAY INVISIBLE (1350 3950);
FORCEPROP 2 LAST CDS_LOCATION J4A2
J 0
(1350 3900);
DISPLAY 0.617021 (1350 3900);
PAINT AQUA (1350 3900);
DISPLAY INVISIBLE (1350 3900);
FORCEPROP 1 LAST PATH I43
J 0
(1800 3850);
PAINT GREEN (1800 3850);
DISPLAY INVISIBLE (1800 3850);
FORCEPROP 2 LAST ROOM DDR4_CH_E
J 0
(1800 2500);
PAINT ORANGE (1800 2500);
DISPLAY INVISIBLE (1800 2500);
FORCEADD GND..1
R 2
(1100 1200);
FORCEPROP 3 LASTPIN (1100 1250) SIG_NAME GND\g
J 0
(1110 1260);
DISPLAY 0.659574 (1110 1260);
PAINT MONO (1110 1260);
DISPLAY INVISIBLE (1110 1260);
FORCEPROP 1 LAST VOLTAGE 0
J 0
(1100 1200);
PAINT SKYBLUE (1100 1200);
DISPLAY INVISIBLE (1100 1200);
FORCEPROP 1 LAST SIZE 1B
J 2
(1025 1150);
DISPLAY 1.170213 (1025 1150);
PAINT GREEN (1025 1150);
DISPLAY INVISIBLE (1025 1150);
FORCEPROP 2 LAST CDS_LIB mstr_symbols
J 0
(1100 1200);
DISPLAY 0.787234 (1100 1200);
PAINT MONO (1100 1200);
DISPLAY INVISIBLE (1100 1200);
FORCEPROP 2 LAST BOM_COST MEM
J 0
(1100 1205);
PAINT ORANGE (1100 1205);
DISPLAY INVISIBLE (1100 1205);
FORCEPROP 1 LAST BODY_TYPE PLUMBING
J 2
(1145 1157);
DISPLAY 0.340426 (1145 1157);
PAINT GREEN (1145 1157);
DISPLAY INVISIBLE (1145 1157);
FORCEPROP 1 LAST PATH I44
J 2
(1025 1200);
DISPLAY 0.936170 (1025 1200);
PAINT GREEN (1025 1200);
DISPLAY INVISIBLE (1025 1200);
FORCEPROP 2 LAST ROOM DDR4_CH_B
J 0
(1100 1205);
PAINT ORANGE (1100 1205);
DISPLAY INVISIBLE (1100 1205);
FORCEPROP 1 LAST HDL_POWER GND
J 2
(1100 1350);
DISPLAY 0.553191 (1100 1350);
PAINT GREEN (1100 1350);
DISPLAY INVISIBLE (1100 1350);
FORCEADD OFFPAGE..3
(-1050 4950);
FORCEPROP 2 LAST $XR0 27 
J 0
(-836 4950);
DISPLAY 0.638298 (-836 4950);
PAINT MONO (-836 4950);
FORCEPROP 2 LAST $XR1 52 
J 0
(-746 4950);
DISPLAY 0.638298 (-746 4950);
PAINT MONO (-746 4950);
FORCEPROP 2 LAST CDS_LIB mstr_standard
J 0
(-1050 4950);
DISPLAY 0.787234 (-1050 4950);
PAINT MONO (-1050 4950);
DISPLAY INVISIBLE (-1050 4950);
FORCEPROP 1 LAST OFFPAGE TRUE
J 0
(-725 4825);
DISPLAY 0.936170 (-725 4825);
PAINT GREEN (-725 4825);
DISPLAY INVISIBLE (-725 4825);
FORCEPROP 1 LAST COMMENT_BODY TRUE
J 0
(-1100 4850);
DISPLAY 0.936170 (-1100 4850);
PAINT GREEN (-1100 4850);
DISPLAY INVISIBLE (-1100 4850);
FORCEPROP 2 LAST PATH I45
J 0
(-850 5025);
DISPLAY 0.787234 (-850 5025);
PAINT MONO (-850 5025);
DISPLAY INVISIBLE (-850 5025);
FORCEADD TAP..6
R 2
(-1600 4900);
FORCEPROP 3 LASTPIN (-1650 4900) SIG_NAME M_E_DQ<62>
J 0
(-1640 4910);
DISPLAY 0.659574 (-1640 4910);
PAINT MONO (-1640 4910);
DISPLAY INVISIBLE (-1640 4910);
FORCEPROP 1 LASTPIN (-1650 4900) BN 62
J 2
(-1600 4910);
DISPLAY 0.617021 (-1600 4910);
PAINT PINK (-1600 4910);
FORCEPROP 2 LAST CDS_LIB mstr_standard
J 2
(-1600 4900);
DISPLAY 0.787234 (-1600 4900);
PAINT MONO (-1600 4900);
DISPLAY INVISIBLE (-1600 4900);
FORCEPROP 1 LAST BODY_TYPE PLUMBING
J 2
(-1600 4850);
DISPLAY 1.234043 (-1600 4850);
PAINT GREEN (-1600 4850);
DISPLAY INVISIBLE (-1600 4850);
FORCEPROP 1 LAST HDL_TAP TRUE
J 2
(-1925 4775);
DISPLAY 1.234043 (-1925 4775);
PAINT GREEN (-1925 4775);
DISPLAY INVISIBLE (-1925 4775);
FORCEPROP 1 LAST PATH I46
J 2
(-1600 4900);
DISPLAY 0.936170 (-1600 4900);
PAINT GREEN (-1600 4900);
DISPLAY INVISIBLE (-1600 4900);
FORCEADD TAP..6
R 2
(-1600 4850);
FORCEPROP 3 LASTPIN (-1650 4850) SIG_NAME M_E_DQ<63>
J 0
(-1640 4860);
DISPLAY 0.659574 (-1640 4860);
PAINT MONO (-1640 4860);
DISPLAY INVISIBLE (-1640 4860);
FORCEPROP 1 LASTPIN (-1650 4850) BN 63
J 2
(-1600 4860);
DISPLAY 0.617021 (-1600 4860);
PAINT PINK (-1600 4860);
FORCEPROP 2 LAST CDS_LIB mstr_standard
J 2
(-1600 4850);
DISPLAY 0.787234 (-1600 4850);
PAINT MONO (-1600 4850);
DISPLAY INVISIBLE (-1600 4850);
FORCEPROP 1 LAST BODY_TYPE PLUMBING
J 2
(-1600 4800);
DISPLAY 1.234043 (-1600 4800);
PAINT GREEN (-1600 4800);
DISPLAY INVISIBLE (-1600 4800);
FORCEPROP 1 LAST HDL_TAP TRUE
J 2
(-1925 4725);
DISPLAY 1.234043 (-1925 4725);
PAINT GREEN (-1925 4725);
DISPLAY INVISIBLE (-1925 4725);
FORCEPROP 1 LAST PATH I47
J 2
(-1600 4850);
DISPLAY 0.936170 (-1600 4850);
PAINT GREEN (-1600 4850);
DISPLAY INVISIBLE (-1600 4850);
FORCEADD TAP..6
R 2
(-1600 4750);
FORCEPROP 3 LASTPIN (-1650 4750) SIG_NAME M_E_DQ<61>
J 0
(-1640 4760);
DISPLAY 0.659574 (-1640 4760);
PAINT MONO (-1640 4760);
DISPLAY INVISIBLE (-1640 4760);
FORCEPROP 1 LASTPIN (-1650 4750) BN 61
J 2
(-1600 4760);
DISPLAY 0.617021 (-1600 4760);
PAINT PINK (-1600 4760);
FORCEPROP 2 LAST CDS_LIB mstr_standard
J 2
(-1600 4750);
DISPLAY 0.787234 (-1600 4750);
PAINT MONO (-1600 4750);
DISPLAY INVISIBLE (-1600 4750);
FORCEPROP 1 LAST BODY_TYPE PLUMBING
J 2
(-1600 4700);
DISPLAY 1.234043 (-1600 4700);
PAINT GREEN (-1600 4700);
DISPLAY INVISIBLE (-1600 4700);
FORCEPROP 1 LAST HDL_TAP TRUE
J 2
(-1925 4625);
DISPLAY 1.234043 (-1925 4625);
PAINT GREEN (-1925 4625);
DISPLAY INVISIBLE (-1925 4625);
FORCEPROP 1 LAST PATH I48
J 2
(-1600 4750);
DISPLAY 0.936170 (-1600 4750);
PAINT GREEN (-1600 4750);
DISPLAY INVISIBLE (-1600 4750);
FORCEADD TAP..6
R 2
(-1600 4800);
FORCEPROP 3 LASTPIN (-1650 4800) SIG_NAME M_E_DQ<60>
J 0
(-1640 4810);
DISPLAY 0.659574 (-1640 4810);
PAINT MONO (-1640 4810);
DISPLAY INVISIBLE (-1640 4810);
FORCEPROP 1 LASTPIN (-1650 4800) BN 60
J 2
(-1600 4810);
DISPLAY 0.617021 (-1600 4810);
PAINT PINK (-1600 4810);
FORCEPROP 2 LAST CDS_LIB mstr_standard
J 2
(-1600 4800);
DISPLAY 0.787234 (-1600 4800);
PAINT MONO (-1600 4800);
DISPLAY INVISIBLE (-1600 4800);
FORCEPROP 1 LAST BODY_TYPE PLUMBING
J 2
(-1600 4750);
DISPLAY 1.234043 (-1600 4750);
PAINT GREEN (-1600 4750);
DISPLAY INVISIBLE (-1600 4750);
FORCEPROP 1 LAST HDL_TAP TRUE
J 2
(-1925 4675);
DISPLAY 1.234043 (-1925 4675);
PAINT GREEN (-1925 4675);
DISPLAY INVISIBLE (-1925 4675);
FORCEPROP 1 LAST PATH I49
J 2
(-1600 4800);
DISPLAY 0.936170 (-1600 4800);
PAINT GREEN (-1600 4800);
DISPLAY INVISIBLE (-1600 4800);
FORCEADD TAP..6
R 2
(900 5000);
FORCEPROP 3 LASTPIN (850 5000) SIG_NAME M_E_DQS_DN<16>
J 0
(860 5010);
DISPLAY 0.659574 (860 5010);
PAINT MONO (860 5010);
DISPLAY INVISIBLE (860 5010);
FORCEPROP 1 LASTPIN (850 5000) BN 16
J 2
(900 5010);
DISPLAY 0.617021 (900 5010);
PAINT PINK (900 5010);
FORCEPROP 2 LAST CDS_LIB mstr_standard
J 0
(900 5000);
DISPLAY 0.787234 (900 5000);
PAINT MONO (900 5000);
DISPLAY INVISIBLE (900 5000);
FORCEPROP 1 LAST BODY_TYPE PLUMBING
J 2
(900 4950);
DISPLAY 1.234043 (900 4950);
PAINT GREEN (900 4950);
DISPLAY INVISIBLE (900 4950);
FORCEPROP 1 LAST HDL_TAP TRUE
J 2
(575 4875);
DISPLAY 1.234043 (575 4875);
PAINT GREEN (575 4875);
DISPLAY INVISIBLE (575 4875);
FORCEPROP 1 LAST PATH I5
J 2
(900 5000);
DISPLAY 0.936170 (900 5000);
PAINT GREEN (900 5000);
DISPLAY INVISIBLE (900 5000);
FORCEADD TAP..6
R 2
(-1600 4700);
FORCEPROP 3 LASTPIN (-1650 4700) SIG_NAME M_E_DQ<58>
J 0
(-1640 4710);
DISPLAY 0.659574 (-1640 4710);
PAINT MONO (-1640 4710);
DISPLAY INVISIBLE (-1640 4710);
FORCEPROP 1 LASTPIN (-1650 4700) BN 58
J 2
(-1600 4710);
DISPLAY 0.617021 (-1600 4710);
PAINT PINK (-1600 4710);
FORCEPROP 2 LAST CDS_LIB mstr_standard
J 2
(-1600 4700);
DISPLAY 0.787234 (-1600 4700);
PAINT MONO (-1600 4700);
DISPLAY INVISIBLE (-1600 4700);
FORCEPROP 1 LAST BODY_TYPE PLUMBING
J 2
(-1600 4650);
DISPLAY 1.234043 (-1600 4650);
PAINT GREEN (-1600 4650);
DISPLAY INVISIBLE (-1600 4650);
FORCEPROP 1 LAST HDL_TAP TRUE
J 2
(-1925 4575);
DISPLAY 1.234043 (-1925 4575);
PAINT GREEN (-1925 4575);
DISPLAY INVISIBLE (-1925 4575);
FORCEPROP 1 LAST PATH I50
J 2
(-1600 4700);
DISPLAY 0.936170 (-1600 4700);
PAINT GREEN (-1600 4700);
DISPLAY INVISIBLE (-1600 4700);
FORCEADD TAP..6
R 2
(-1600 4600);
FORCEPROP 3 LASTPIN (-1650 4600) SIG_NAME M_E_DQ<56>
J 0
(-1640 4610);
DISPLAY 0.659574 (-1640 4610);
PAINT MONO (-1640 4610);
DISPLAY INVISIBLE (-1640 4610);
FORCEPROP 1 LASTPIN (-1650 4600) BN 56
J 2
(-1600 4610);
DISPLAY 0.617021 (-1600 4610);
PAINT PINK (-1600 4610);
FORCEPROP 2 LAST CDS_LIB mstr_standard
J 2
(-1600 4600);
DISPLAY 0.787234 (-1600 4600);
PAINT MONO (-1600 4600);
DISPLAY INVISIBLE (-1600 4600);
FORCEPROP 1 LAST BODY_TYPE PLUMBING
J 2
(-1600 4550);
DISPLAY 1.234043 (-1600 4550);
PAINT GREEN (-1600 4550);
DISPLAY INVISIBLE (-1600 4550);
FORCEPROP 1 LAST HDL_TAP TRUE
J 2
(-1925 4475);
DISPLAY 1.234043 (-1925 4475);
PAINT GREEN (-1925 4475);
DISPLAY INVISIBLE (-1925 4475);
FORCEPROP 1 LAST PATH I51
J 2
(-1600 4600);
DISPLAY 0.936170 (-1600 4600);
PAINT GREEN (-1600 4600);
DISPLAY INVISIBLE (-1600 4600);
FORCEADD TAP..6
R 2
(-1600 4650);
FORCEPROP 3 LASTPIN (-1650 4650) SIG_NAME M_E_DQ<59>
J 0
(-1640 4660);
DISPLAY 0.659574 (-1640 4660);
PAINT MONO (-1640 4660);
DISPLAY INVISIBLE (-1640 4660);
FORCEPROP 1 LASTPIN (-1650 4650) BN 59
J 2
(-1600 4660);
DISPLAY 0.617021 (-1600 4660);
PAINT PINK (-1600 4660);
FORCEPROP 2 LAST CDS_LIB mstr_standard
J 2
(-1600 4650);
DISPLAY 0.787234 (-1600 4650);
PAINT MONO (-1600 4650);
DISPLAY INVISIBLE (-1600 4650);
FORCEPROP 1 LAST BODY_TYPE PLUMBING
J 2
(-1600 4600);
DISPLAY 1.234043 (-1600 4600);
PAINT GREEN (-1600 4600);
DISPLAY INVISIBLE (-1600 4600);
FORCEPROP 1 LAST HDL_TAP TRUE
J 2
(-1925 4525);
DISPLAY 1.234043 (-1925 4525);
PAINT GREEN (-1925 4525);
DISPLAY INVISIBLE (-1925 4525);
FORCEPROP 1 LAST PATH I52
J 2
(-1600 4650);
DISPLAY 0.936170 (-1600 4650);
PAINT GREEN (-1600 4650);
DISPLAY INVISIBLE (-1600 4650);
FORCEADD TAP..6
R 2
(-1600 4550);
FORCEPROP 3 LASTPIN (-1650 4550) SIG_NAME M_E_DQ<57>
J 0
(-1640 4560);
DISPLAY 0.659574 (-1640 4560);
PAINT MONO (-1640 4560);
DISPLAY INVISIBLE (-1640 4560);
FORCEPROP 1 LASTPIN (-1650 4550) BN 57
J 2
(-1600 4560);
DISPLAY 0.617021 (-1600 4560);
PAINT PINK (-1600 4560);
FORCEPROP 2 LAST CDS_LIB mstr_standard
J 2
(-1600 4550);
DISPLAY 0.787234 (-1600 4550);
PAINT MONO (-1600 4550);
DISPLAY INVISIBLE (-1600 4550);
FORCEPROP 1 LAST BODY_TYPE PLUMBING
J 2
(-1600 4500);
DISPLAY 1.234043 (-1600 4500);
PAINT GREEN (-1600 4500);
DISPLAY INVISIBLE (-1600 4500);
FORCEPROP 1 LAST HDL_TAP TRUE
J 2
(-1925 4425);
DISPLAY 1.234043 (-1925 4425);
PAINT GREEN (-1925 4425);
DISPLAY INVISIBLE (-1925 4425);
FORCEPROP 1 LAST PATH I53
J 2
(-1600 4550);
DISPLAY 0.936170 (-1600 4550);
PAINT GREEN (-1600 4550);
DISPLAY INVISIBLE (-1600 4550);
FORCEADD TAP..6
R 2
(-1600 4500);
FORCEPROP 3 LASTPIN (-1650 4500) SIG_NAME M_E_DQ<54>
J 0
(-1640 4510);
DISPLAY 0.659574 (-1640 4510);
PAINT MONO (-1640 4510);
DISPLAY INVISIBLE (-1640 4510);
FORCEPROP 1 LASTPIN (-1650 4500) BN 54
J 2
(-1600 4510);
DISPLAY 0.617021 (-1600 4510);
PAINT PINK (-1600 4510);
FORCEPROP 2 LAST CDS_LIB mstr_standard
J 2
(-1600 4500);
DISPLAY 0.787234 (-1600 4500);
PAINT MONO (-1600 4500);
DISPLAY INVISIBLE (-1600 4500);
FORCEPROP 1 LAST BODY_TYPE PLUMBING
J 2
(-1600 4450);
DISPLAY 1.234043 (-1600 4450);
PAINT GREEN (-1600 4450);
DISPLAY INVISIBLE (-1600 4450);
FORCEPROP 1 LAST HDL_TAP TRUE
J 2
(-1925 4375);
DISPLAY 1.234043 (-1925 4375);
PAINT GREEN (-1925 4375);
DISPLAY INVISIBLE (-1925 4375);
FORCEPROP 1 LAST PATH I54
J 2
(-1600 4500);
DISPLAY 0.936170 (-1600 4500);
PAINT GREEN (-1600 4500);
DISPLAY INVISIBLE (-1600 4500);
FORCEADD TAP..6
R 2
(-1600 4400);
FORCEPROP 3 LASTPIN (-1650 4400) SIG_NAME M_E_DQ<52>
J 0
(-1640 4410);
DISPLAY 0.659574 (-1640 4410);
PAINT MONO (-1640 4410);
DISPLAY INVISIBLE (-1640 4410);
FORCEPROP 1 LASTPIN (-1650 4400) BN 52
J 2
(-1600 4410);
DISPLAY 0.617021 (-1600 4410);
PAINT PINK (-1600 4410);
FORCEPROP 2 LAST CDS_LIB mstr_standard
J 2
(-1600 4400);
DISPLAY 0.787234 (-1600 4400);
PAINT MONO (-1600 4400);
DISPLAY INVISIBLE (-1600 4400);
FORCEPROP 1 LAST BODY_TYPE PLUMBING
J 2
(-1600 4350);
DISPLAY 1.234043 (-1600 4350);
PAINT GREEN (-1600 4350);
DISPLAY INVISIBLE (-1600 4350);
FORCEPROP 1 LAST HDL_TAP TRUE
J 2
(-1925 4275);
DISPLAY 1.234043 (-1925 4275);
PAINT GREEN (-1925 4275);
DISPLAY INVISIBLE (-1925 4275);
FORCEPROP 1 LAST PATH I55
J 2
(-1600 4400);
DISPLAY 0.936170 (-1600 4400);
PAINT GREEN (-1600 4400);
DISPLAY INVISIBLE (-1600 4400);
FORCEADD TAP..6
R 2
(-1600 4450);
FORCEPROP 3 LASTPIN (-1650 4450) SIG_NAME M_E_DQ<55>
J 0
(-1640 4460);
DISPLAY 0.659574 (-1640 4460);
PAINT MONO (-1640 4460);
DISPLAY INVISIBLE (-1640 4460);
FORCEPROP 1 LASTPIN (-1650 4450) BN 55
J 2
(-1600 4460);
DISPLAY 0.617021 (-1600 4460);
PAINT PINK (-1600 4460);
FORCEPROP 2 LAST CDS_LIB mstr_standard
J 2
(-1600 4450);
DISPLAY 0.787234 (-1600 4450);
PAINT MONO (-1600 4450);
DISPLAY INVISIBLE (-1600 4450);
FORCEPROP 1 LAST BODY_TYPE PLUMBING
J 2
(-1600 4400);
DISPLAY 1.234043 (-1600 4400);
PAINT GREEN (-1600 4400);
DISPLAY INVISIBLE (-1600 4400);
FORCEPROP 1 LAST HDL_TAP TRUE
J 2
(-1925 4325);
DISPLAY 1.234043 (-1925 4325);
PAINT GREEN (-1925 4325);
DISPLAY INVISIBLE (-1925 4325);
FORCEPROP 1 LAST PATH I56
J 2
(-1600 4450);
DISPLAY 0.936170 (-1600 4450);
PAINT GREEN (-1600 4450);
DISPLAY INVISIBLE (-1600 4450);
FORCEADD TAP..6
R 2
(-1600 4350);
FORCEPROP 3 LASTPIN (-1650 4350) SIG_NAME M_E_DQ<53>
J 0
(-1640 4360);
DISPLAY 0.659574 (-1640 4360);
PAINT MONO (-1640 4360);
DISPLAY INVISIBLE (-1640 4360);
FORCEPROP 1 LASTPIN (-1650 4350) BN 53
J 2
(-1600 4360);
DISPLAY 0.617021 (-1600 4360);
PAINT PINK (-1600 4360);
FORCEPROP 2 LAST CDS_LIB mstr_standard
J 2
(-1600 4350);
DISPLAY 0.787234 (-1600 4350);
PAINT MONO (-1600 4350);
DISPLAY INVISIBLE (-1600 4350);
FORCEPROP 1 LAST BODY_TYPE PLUMBING
J 2
(-1600 4300);
DISPLAY 1.234043 (-1600 4300);
PAINT GREEN (-1600 4300);
DISPLAY INVISIBLE (-1600 4300);
FORCEPROP 1 LAST HDL_TAP TRUE
J 2
(-1925 4225);
DISPLAY 1.234043 (-1925 4225);
PAINT GREEN (-1925 4225);
DISPLAY INVISIBLE (-1925 4225);
FORCEPROP 1 LAST PATH I57
J 2
(-1600 4350);
DISPLAY 0.936170 (-1600 4350);
PAINT GREEN (-1600 4350);
DISPLAY INVISIBLE (-1600 4350);
FORCEADD TAP..6
R 2
(-1600 4300);
FORCEPROP 3 LASTPIN (-1650 4300) SIG_NAME M_E_DQ<50>
J 0
(-1640 4310);
DISPLAY 0.659574 (-1640 4310);
PAINT MONO (-1640 4310);
DISPLAY INVISIBLE (-1640 4310);
FORCEPROP 1 LASTPIN (-1650 4300) BN 50
J 2
(-1600 4310);
DISPLAY 0.617021 (-1600 4310);
PAINT PINK (-1600 4310);
FORCEPROP 2 LAST CDS_LIB mstr_standard
J 2
(-1600 4300);
DISPLAY 0.787234 (-1600 4300);
PAINT MONO (-1600 4300);
DISPLAY INVISIBLE (-1600 4300);
FORCEPROP 1 LAST BODY_TYPE PLUMBING
J 2
(-1600 4250);
DISPLAY 1.234043 (-1600 4250);
PAINT GREEN (-1600 4250);
DISPLAY INVISIBLE (-1600 4250);
FORCEPROP 1 LAST HDL_TAP TRUE
J 2
(-1925 4175);
DISPLAY 1.234043 (-1925 4175);
PAINT GREEN (-1925 4175);
DISPLAY INVISIBLE (-1925 4175);
FORCEPROP 1 LAST PATH I58
J 2
(-1600 4300);
DISPLAY 0.936170 (-1600 4300);
PAINT GREEN (-1600 4300);
DISPLAY INVISIBLE (-1600 4300);
FORCEADD TAP..6
R 2
(-1600 4250);
FORCEPROP 3 LASTPIN (-1650 4250) SIG_NAME M_E_DQ<51>
J 0
(-1640 4260);
DISPLAY 0.659574 (-1640 4260);
PAINT MONO (-1640 4260);
DISPLAY INVISIBLE (-1640 4260);
FORCEPROP 1 LASTPIN (-1650 4250) BN 51
J 2
(-1600 4260);
DISPLAY 0.617021 (-1600 4260);
PAINT PINK (-1600 4260);
FORCEPROP 2 LAST CDS_LIB mstr_standard
J 2
(-1600 4250);
DISPLAY 0.787234 (-1600 4250);
PAINT MONO (-1600 4250);
DISPLAY INVISIBLE (-1600 4250);
FORCEPROP 1 LAST BODY_TYPE PLUMBING
J 2
(-1600 4200);
DISPLAY 1.234043 (-1600 4200);
PAINT GREEN (-1600 4200);
DISPLAY INVISIBLE (-1600 4200);
FORCEPROP 1 LAST HDL_TAP TRUE
J 2
(-1925 4125);
DISPLAY 1.234043 (-1925 4125);
PAINT GREEN (-1925 4125);
DISPLAY INVISIBLE (-1925 4125);
FORCEPROP 1 LAST PATH I59
J 2
(-1600 4250);
DISPLAY 0.936170 (-1600 4250);
PAINT GREEN (-1600 4250);
DISPLAY INVISIBLE (-1600 4250);
FORCEADD TAP..6
R 2
(900 4900);
FORCEPROP 3 LASTPIN (850 4900) SIG_NAME M_E_DQS_DN<15>
J 0
(860 4910);
DISPLAY 0.659574 (860 4910);
PAINT MONO (860 4910);
DISPLAY INVISIBLE (860 4910);
FORCEPROP 1 LASTPIN (850 4900) BN 15
J 2
(900 4910);
DISPLAY 0.617021 (900 4910);
PAINT PINK (900 4910);
FORCEPROP 2 LAST CDS_LIB mstr_standard
J 0
(900 4900);
DISPLAY 0.787234 (900 4900);
PAINT MONO (900 4900);
DISPLAY INVISIBLE (900 4900);
FORCEPROP 1 LAST BODY_TYPE PLUMBING
J 2
(900 4850);
DISPLAY 1.234043 (900 4850);
PAINT GREEN (900 4850);
DISPLAY INVISIBLE (900 4850);
FORCEPROP 1 LAST HDL_TAP TRUE
J 2
(575 4775);
DISPLAY 1.234043 (575 4775);
PAINT GREEN (575 4775);
DISPLAY INVISIBLE (575 4775);
FORCEPROP 1 LAST PATH I6
J 2
(900 4900);
DISPLAY 0.936170 (900 4900);
PAINT GREEN (900 4900);
DISPLAY INVISIBLE (900 4900);
FORCEADD TAP..6
R 2
(-1600 4200);
FORCEPROP 3 LASTPIN (-1650 4200) SIG_NAME M_E_DQ<48>
J 0
(-1640 4210);
DISPLAY 0.659574 (-1640 4210);
PAINT MONO (-1640 4210);
DISPLAY INVISIBLE (-1640 4210);
FORCEPROP 1 LASTPIN (-1650 4200) BN 48
J 2
(-1600 4210);
DISPLAY 0.617021 (-1600 4210);
PAINT PINK (-1600 4210);
FORCEPROP 2 LAST CDS_LIB mstr_standard
J 2
(-1600 4200);
DISPLAY 0.787234 (-1600 4200);
PAINT MONO (-1600 4200);
DISPLAY INVISIBLE (-1600 4200);
FORCEPROP 1 LAST BODY_TYPE PLUMBING
J 2
(-1600 4150);
DISPLAY 1.234043 (-1600 4150);
PAINT GREEN (-1600 4150);
DISPLAY INVISIBLE (-1600 4150);
FORCEPROP 1 LAST HDL_TAP TRUE
J 2
(-1925 4075);
DISPLAY 1.234043 (-1925 4075);
PAINT GREEN (-1925 4075);
DISPLAY INVISIBLE (-1925 4075);
FORCEPROP 1 LAST PATH I60
J 2
(-1600 4200);
DISPLAY 0.936170 (-1600 4200);
PAINT GREEN (-1600 4200);
DISPLAY INVISIBLE (-1600 4200);
FORCEADD TAP..6
R 2
(-1600 4100);
FORCEPROP 3 LASTPIN (-1650 4100) SIG_NAME M_E_DQ<46>
J 0
(-1640 4110);
DISPLAY 0.659574 (-1640 4110);
PAINT MONO (-1640 4110);
DISPLAY INVISIBLE (-1640 4110);
FORCEPROP 1 LASTPIN (-1650 4100) BN 46
J 2
(-1600 4110);
DISPLAY 0.617021 (-1600 4110);
PAINT PINK (-1600 4110);
FORCEPROP 2 LAST CDS_LIB mstr_standard
J 2
(-1600 4100);
DISPLAY 0.787234 (-1600 4100);
PAINT MONO (-1600 4100);
DISPLAY INVISIBLE (-1600 4100);
FORCEPROP 1 LAST BODY_TYPE PLUMBING
J 2
(-1600 4050);
DISPLAY 1.234043 (-1600 4050);
PAINT GREEN (-1600 4050);
DISPLAY INVISIBLE (-1600 4050);
FORCEPROP 1 LAST HDL_TAP TRUE
J 2
(-1925 3975);
DISPLAY 1.234043 (-1925 3975);
PAINT GREEN (-1925 3975);
DISPLAY INVISIBLE (-1925 3975);
FORCEPROP 1 LAST PATH I61
J 2
(-1600 4100);
DISPLAY 0.936170 (-1600 4100);
PAINT GREEN (-1600 4100);
DISPLAY INVISIBLE (-1600 4100);
FORCEADD TAP..6
R 2
(-1600 4150);
FORCEPROP 3 LASTPIN (-1650 4150) SIG_NAME M_E_DQ<49>
J 0
(-1640 4160);
DISPLAY 0.659574 (-1640 4160);
PAINT MONO (-1640 4160);
DISPLAY INVISIBLE (-1640 4160);
FORCEPROP 1 LASTPIN (-1650 4150) BN 49
J 2
(-1600 4160);
DISPLAY 0.617021 (-1600 4160);
PAINT PINK (-1600 4160);
FORCEPROP 2 LAST CDS_LIB mstr_standard
J 2
(-1600 4150);
DISPLAY 0.787234 (-1600 4150);
PAINT MONO (-1600 4150);
DISPLAY INVISIBLE (-1600 4150);
FORCEPROP 1 LAST BODY_TYPE PLUMBING
J 2
(-1600 4100);
DISPLAY 1.234043 (-1600 4100);
PAINT GREEN (-1600 4100);
DISPLAY INVISIBLE (-1600 4100);
FORCEPROP 1 LAST HDL_TAP TRUE
J 2
(-1925 4025);
DISPLAY 1.234043 (-1925 4025);
PAINT GREEN (-1925 4025);
DISPLAY INVISIBLE (-1925 4025);
FORCEPROP 1 LAST PATH I62
J 2
(-1600 4150);
DISPLAY 0.936170 (-1600 4150);
PAINT GREEN (-1600 4150);
DISPLAY INVISIBLE (-1600 4150);
FORCEADD TAP..6
R 2
(-1600 4050);
FORCEPROP 3 LASTPIN (-1650 4050) SIG_NAME M_E_DQ<47>
J 0
(-1640 4060);
DISPLAY 0.659574 (-1640 4060);
PAINT MONO (-1640 4060);
DISPLAY INVISIBLE (-1640 4060);
FORCEPROP 1 LASTPIN (-1650 4050) BN 47
J 2
(-1600 4060);
DISPLAY 0.617021 (-1600 4060);
PAINT PINK (-1600 4060);
FORCEPROP 2 LAST CDS_LIB mstr_standard
J 2
(-1600 4050);
DISPLAY 0.787234 (-1600 4050);
PAINT MONO (-1600 4050);
DISPLAY INVISIBLE (-1600 4050);
FORCEPROP 1 LAST BODY_TYPE PLUMBING
J 2
(-1600 4000);
DISPLAY 1.234043 (-1600 4000);
PAINT GREEN (-1600 4000);
DISPLAY INVISIBLE (-1600 4000);
FORCEPROP 1 LAST HDL_TAP TRUE
J 2
(-1925 3925);
DISPLAY 1.234043 (-1925 3925);
PAINT GREEN (-1925 3925);
DISPLAY INVISIBLE (-1925 3925);
FORCEPROP 1 LAST PATH I63
J 2
(-1600 4050);
DISPLAY 0.936170 (-1600 4050);
PAINT GREEN (-1600 4050);
DISPLAY INVISIBLE (-1600 4050);
FORCEADD TAP..6
R 2
(-1600 4000);
FORCEPROP 3 LASTPIN (-1650 4000) SIG_NAME M_E_DQ<44>
J 0
(-1640 4010);
DISPLAY 0.659574 (-1640 4010);
PAINT MONO (-1640 4010);
DISPLAY INVISIBLE (-1640 4010);
FORCEPROP 1 LASTPIN (-1650 4000) BN 44
J 2
(-1600 4010);
DISPLAY 0.617021 (-1600 4010);
PAINT PINK (-1600 4010);
FORCEPROP 2 LAST CDS_LIB mstr_standard
J 2
(-1600 4000);
DISPLAY 0.787234 (-1600 4000);
PAINT MONO (-1600 4000);
DISPLAY INVISIBLE (-1600 4000);
FORCEPROP 1 LAST BODY_TYPE PLUMBING
J 2
(-1600 3950);
DISPLAY 1.234043 (-1600 3950);
PAINT GREEN (-1600 3950);
DISPLAY INVISIBLE (-1600 3950);
FORCEPROP 1 LAST HDL_TAP TRUE
J 2
(-1925 3875);
DISPLAY 1.234043 (-1925 3875);
PAINT GREEN (-1925 3875);
DISPLAY INVISIBLE (-1925 3875);
FORCEPROP 1 LAST PATH I64
J 2
(-1600 4000);
DISPLAY 0.936170 (-1600 4000);
PAINT GREEN (-1600 4000);
DISPLAY INVISIBLE (-1600 4000);
FORCEADD TAP..6
R 2
(-1600 3950);
FORCEPROP 3 LASTPIN (-1650 3950) SIG_NAME M_E_DQ<45>
J 0
(-1640 3960);
DISPLAY 0.659574 (-1640 3960);
PAINT MONO (-1640 3960);
DISPLAY INVISIBLE (-1640 3960);
FORCEPROP 1 LASTPIN (-1650 3950) BN 45
J 2
(-1600 3960);
DISPLAY 0.617021 (-1600 3960);
PAINT PINK (-1600 3960);
FORCEPROP 2 LAST CDS_LIB mstr_standard
J 2
(-1600 3950);
DISPLAY 0.787234 (-1600 3950);
PAINT MONO (-1600 3950);
DISPLAY INVISIBLE (-1600 3950);
FORCEPROP 1 LAST BODY_TYPE PLUMBING
J 2
(-1600 3900);
DISPLAY 1.234043 (-1600 3900);
PAINT GREEN (-1600 3900);
DISPLAY INVISIBLE (-1600 3900);
FORCEPROP 1 LAST HDL_TAP TRUE
J 2
(-1925 3825);
DISPLAY 1.234043 (-1925 3825);
PAINT GREEN (-1925 3825);
DISPLAY INVISIBLE (-1925 3825);
FORCEPROP 1 LAST PATH I65
J 2
(-1600 3950);
DISPLAY 0.936170 (-1600 3950);
PAINT GREEN (-1600 3950);
DISPLAY INVISIBLE (-1600 3950);
FORCEADD SCONN288_H44441004..2
(0 4300);
FORCEPROP 1 LAST LOCATION J4A2
J 0
(-400 5400);
DISPLAY 0.617021 (-400 5400);
PAINT AQUA (-400 5400);
FORCEPROP 1 LAST PART_NUMBER H44441-004
J 0
(-400 3200);
DISPLAY 0.617021 (-400 3200);
PAINT BLUE (-400 3200);
FORCEPROP 1 LAST MATERIAL SCONN
J 0
(-400 5350);
DISPLAY 0.617021 (-400 5350);
PAINT SKYBLUE (-400 5350);
FORCEPROP 2 LASTPIN (450 5150) $PN 51
J 0
(460 5160);
DISPLAY 0.617021 (460 5160);
PAINT ORANGE (460 5160);
FORCEPROP 2 LASTPIN (450 5100) $PN 52
J 0
(460 5110);
DISPLAY 0.617021 (460 5110);
PAINT ORANGE (460 5110);
FORCEPROP 2 LASTPIN (450 5050) $PN 132
J 0
(460 5060);
DISPLAY 0.617021 (460 5060);
PAINT ORANGE (460 5060);
FORCEPROP 2 LASTPIN (450 5000) $PN 133
J 0
(460 5010);
DISPLAY 0.617021 (460 5010);
PAINT ORANGE (460 5010);
FORCEPROP 2 LASTPIN (450 4950) $PN 121
J 0
(460 4960);
DISPLAY 0.617021 (460 4960);
PAINT ORANGE (460 4960);
FORCEPROP 2 LASTPIN (450 4900) $PN 122
J 0
(460 4910);
DISPLAY 0.617021 (460 4910);
PAINT ORANGE (460 4910);
FORCEPROP 2 LASTPIN (450 4850) $PN 110
J 0
(460 4860);
DISPLAY 0.617021 (460 4860);
PAINT ORANGE (460 4860);
FORCEPROP 2 LASTPIN (450 4800) $PN 111
J 0
(460 4810);
DISPLAY 0.617021 (460 4810);
PAINT ORANGE (460 4810);
FORCEPROP 2 LASTPIN (450 4750) $PN 99
J 0
(460 4760);
DISPLAY 0.617021 (460 4760);
PAINT ORANGE (460 4760);
FORCEPROP 2 LASTPIN (450 4700) $PN 100
J 0
(460 4710);
DISPLAY 0.617021 (460 4710);
PAINT ORANGE (460 4710);
FORCEPROP 2 LASTPIN (450 4650) $PN 40
J 0
(460 4660);
DISPLAY 0.617021 (460 4660);
PAINT ORANGE (460 4660);
FORCEPROP 2 LASTPIN (450 4600) $PN 41
J 0
(460 4610);
DISPLAY 0.617021 (460 4610);
PAINT ORANGE (460 4610);
FORCEPROP 2 LASTPIN (450 4550) $PN 29
J 0
(460 4560);
DISPLAY 0.617021 (460 4560);
PAINT ORANGE (460 4560);
FORCEPROP 2 LASTPIN (450 4500) $PN 30
J 0
(460 4510);
DISPLAY 0.617021 (460 4510);
PAINT ORANGE (460 4510);
FORCEPROP 2 LASTPIN (450 4450) $PN 18
J 0
(460 4460);
DISPLAY 0.617021 (460 4460);
PAINT ORANGE (460 4460);
FORCEPROP 2 LASTPIN (450 4400) $PN 19
J 0
(460 4410);
DISPLAY 0.617021 (460 4410);
PAINT ORANGE (460 4410);
FORCEPROP 2 LASTPIN (450 4350) $PN 7
J 0
(460 4360);
DISPLAY 0.617021 (460 4360);
PAINT ORANGE (460 4360);
FORCEPROP 2 LASTPIN (450 4300) $PN 8
J 0
(460 4310);
DISPLAY 0.617021 (460 4310);
PAINT ORANGE (460 4310);
FORCEPROP 2 LASTPIN (450 4250) $PN 197
J 0
(460 4260);
DISPLAY 0.617021 (460 4260);
PAINT ORANGE (460 4260);
FORCEPROP 2 LASTPIN (450 4200) $PN 196
J 0
(460 4210);
DISPLAY 0.617021 (460 4210);
PAINT ORANGE (460 4210);
FORCEPROP 2 LASTPIN (450 4150) $PN 278
J 0
(460 4160);
DISPLAY 0.617021 (460 4160);
PAINT ORANGE (460 4160);
FORCEPROP 2 LASTPIN (450 4100) $PN 277
J 0
(460 4110);
DISPLAY 0.617021 (460 4110);
PAINT ORANGE (460 4110);
FORCEPROP 2 LASTPIN (450 4050) $PN 267
J 0
(460 4060);
DISPLAY 0.617021 (460 4060);
PAINT ORANGE (460 4060);
FORCEPROP 2 LASTPIN (450 4000) $PN 266
J 0
(460 4010);
DISPLAY 0.617021 (460 4010);
PAINT ORANGE (460 4010);
FORCEPROP 2 LASTPIN (450 3950) $PN 256
J 0
(460 3960);
DISPLAY 0.617021 (460 3960);
PAINT ORANGE (460 3960);
FORCEPROP 2 LASTPIN (450 3900) $PN 255
J 0
(460 3910);
DISPLAY 0.617021 (460 3910);
PAINT ORANGE (460 3910);
FORCEPROP 2 LASTPIN (450 3850) $PN 245
J 0
(460 3860);
DISPLAY 0.617021 (460 3860);
PAINT ORANGE (460 3860);
FORCEPROP 2 LASTPIN (450 3800) $PN 244
J 0
(460 3810);
DISPLAY 0.617021 (460 3810);
PAINT ORANGE (460 3810);
FORCEPROP 2 LASTPIN (450 3750) $PN 186
J 0
(460 3760);
DISPLAY 0.617021 (460 3760);
PAINT ORANGE (460 3760);
FORCEPROP 2 LASTPIN (450 3700) $PN 185
J 0
(460 3710);
DISPLAY 0.617021 (460 3710);
PAINT ORANGE (460 3710);
FORCEPROP 2 LASTPIN (450 3650) $PN 175
J 0
(460 3660);
DISPLAY 0.617021 (460 3660);
PAINT ORANGE (460 3660);
FORCEPROP 2 LASTPIN (450 3600) $PN 174
J 0
(460 3610);
DISPLAY 0.617021 (460 3610);
PAINT ORANGE (460 3610);
FORCEPROP 2 LASTPIN (450 3550) $PN 164
J 0
(460 3560);
DISPLAY 0.617021 (460 3560);
PAINT ORANGE (460 3560);
FORCEPROP 2 LASTPIN (450 3500) $PN 163
J 0
(460 3510);
DISPLAY 0.617021 (460 3510);
PAINT ORANGE (460 3510);
FORCEPROP 2 LASTPIN (450 3450) $PN 153
J 0
(460 3460);
DISPLAY 0.617021 (460 3460);
PAINT ORANGE (460 3460);
FORCEPROP 2 LASTPIN (450 3400) $PN 152
J 0
(460 3410);
DISPLAY 0.617021 (460 3410);
PAINT ORANGE (460 3410);
FORCEPROP 1 LAST PACK_TYPE PIP
J 0
(-400 5450);
PAINT SKYBLUE (-400 5450);
DISPLAY INVISIBLE (-400 5450);
FORCEPROP 2 LAST BOM_COST MEM
J 0
(0 4300);
PAINT ORANGE (0 4300);
DISPLAY INVISIBLE (0 4300);
FORCEPROP 2 LAST CDS_LIB mstr_sconn
J 0
(0 4300);
PAINT ORANGE (0 4300);
DISPLAY INVISIBLE (0 4300);
FORCEPROP 2 LAST SEC_TYPE PIP
J 0
(-400 5450);
DISPLAY 1.021277 (-400 5450);
PAINT ORANGE (-400 5450);
DISPLAY INVISIBLE (-400 5450);
FORCEPROP 2 LAST SEC 2
J 0
(-400 5450);
DISPLAY 0.680851 (-400 5450);
PAINT MONO (-400 5450);
DISPLAY INVISIBLE (-400 5450);
FORCEPROP 2 LAST CDS_LOCATION J4A2
J 0
(-400 5400);
DISPLAY 0.617021 (-400 5400);
PAINT AQUA (-400 5400);
DISPLAY INVISIBLE (-400 5400);
FORCEPROP 1 LAST PATH I66
J 0
(0 5350);
PAINT GREEN (0 5350);
DISPLAY INVISIBLE (0 5350);
FORCEPROP 2 LAST ROOM DDR4_CH_E
J 0
(-400 5500);
PAINT ORANGE (-400 5500);
DISPLAY INVISIBLE (-400 5500);
FORCEADD TAP..6
R 2
(-1600 3900);
FORCEPROP 3 LASTPIN (-1650 3900) SIG_NAME M_E_DQ<42>
J 0
(-1640 3910);
DISPLAY 0.659574 (-1640 3910);
PAINT MONO (-1640 3910);
DISPLAY INVISIBLE (-1640 3910);
FORCEPROP 1 LASTPIN (-1650 3900) BN 42
J 2
(-1600 3910);
DISPLAY 0.617021 (-1600 3910);
PAINT PINK (-1600 3910);
FORCEPROP 2 LAST CDS_LIB mstr_standard
J 2
(-1600 3900);
DISPLAY 0.787234 (-1600 3900);
PAINT MONO (-1600 3900);
DISPLAY INVISIBLE (-1600 3900);
FORCEPROP 1 LAST BODY_TYPE PLUMBING
J 2
(-1600 3850);
DISPLAY 1.234043 (-1600 3850);
PAINT GREEN (-1600 3850);
DISPLAY INVISIBLE (-1600 3850);
FORCEPROP 1 LAST HDL_TAP TRUE
J 2
(-1925 3775);
DISPLAY 1.234043 (-1925 3775);
PAINT GREEN (-1925 3775);
DISPLAY INVISIBLE (-1925 3775);
FORCEPROP 1 LAST PATH I67
J 2
(-1600 3900);
DISPLAY 0.936170 (-1600 3900);
PAINT GREEN (-1600 3900);
DISPLAY INVISIBLE (-1600 3900);
FORCEADD TAP..6
R 2
(-1600 3850);
FORCEPROP 3 LASTPIN (-1650 3850) SIG_NAME M_E_DQ<43>
J 0
(-1640 3860);
DISPLAY 0.659574 (-1640 3860);
PAINT MONO (-1640 3860);
DISPLAY INVISIBLE (-1640 3860);
FORCEPROP 1 LASTPIN (-1650 3850) BN 43
J 2
(-1600 3860);
DISPLAY 0.617021 (-1600 3860);
PAINT PINK (-1600 3860);
FORCEPROP 2 LAST CDS_LIB mstr_standard
J 2
(-1600 3850);
DISPLAY 0.787234 (-1600 3850);
PAINT MONO (-1600 3850);
DISPLAY INVISIBLE (-1600 3850);
FORCEPROP 1 LAST BODY_TYPE PLUMBING
J 2
(-1600 3800);
DISPLAY 1.234043 (-1600 3800);
PAINT GREEN (-1600 3800);
DISPLAY INVISIBLE (-1600 3800);
FORCEPROP 1 LAST HDL_TAP TRUE
J 2
(-1925 3725);
DISPLAY 1.234043 (-1925 3725);
PAINT GREEN (-1925 3725);
DISPLAY INVISIBLE (-1925 3725);
FORCEPROP 1 LAST PATH I68
J 2
(-1600 3850);
DISPLAY 0.936170 (-1600 3850);
PAINT GREEN (-1600 3850);
DISPLAY INVISIBLE (-1600 3850);
FORCEADD TAP..6
R 2
(-1600 3750);
FORCEPROP 3 LASTPIN (-1650 3750) SIG_NAME M_E_DQ<41>
J 0
(-1640 3760);
DISPLAY 0.659574 (-1640 3760);
PAINT MONO (-1640 3760);
DISPLAY INVISIBLE (-1640 3760);
FORCEPROP 1 LASTPIN (-1650 3750) BN 41
J 2
(-1600 3760);
DISPLAY 0.617021 (-1600 3760);
PAINT PINK (-1600 3760);
FORCEPROP 2 LAST CDS_LIB mstr_standard
J 2
(-1600 3750);
DISPLAY 0.787234 (-1600 3750);
PAINT MONO (-1600 3750);
DISPLAY INVISIBLE (-1600 3750);
FORCEPROP 1 LAST BODY_TYPE PLUMBING
J 2
(-1600 3700);
DISPLAY 1.234043 (-1600 3700);
PAINT GREEN (-1600 3700);
DISPLAY INVISIBLE (-1600 3700);
FORCEPROP 1 LAST HDL_TAP TRUE
J 2
(-1925 3625);
DISPLAY 1.234043 (-1925 3625);
PAINT GREEN (-1925 3625);
DISPLAY INVISIBLE (-1925 3625);
FORCEPROP 1 LAST PATH I69
J 2
(-1600 3750);
DISPLAY 0.936170 (-1600 3750);
PAINT GREEN (-1600 3750);
DISPLAY INVISIBLE (-1600 3750);
FORCEADD TAP..6
R 2
(900 4700);
FORCEPROP 3 LASTPIN (850 4700) SIG_NAME M_E_DQS_DN<13>
J 0
(860 4710);
DISPLAY 0.659574 (860 4710);
PAINT MONO (860 4710);
DISPLAY INVISIBLE (860 4710);
FORCEPROP 1 LASTPIN (850 4700) BN 13
J 2
(900 4710);
DISPLAY 0.617021 (900 4710);
PAINT PINK (900 4710);
FORCEPROP 2 LAST CDS_LIB mstr_standard
J 0
(900 4700);
DISPLAY 0.787234 (900 4700);
PAINT MONO (900 4700);
DISPLAY INVISIBLE (900 4700);
FORCEPROP 1 LAST BODY_TYPE PLUMBING
J 2
(900 4650);
DISPLAY 1.234043 (900 4650);
PAINT GREEN (900 4650);
DISPLAY INVISIBLE (900 4650);
FORCEPROP 1 LAST HDL_TAP TRUE
J 2
(575 4575);
DISPLAY 1.234043 (575 4575);
PAINT GREEN (575 4575);
DISPLAY INVISIBLE (575 4575);
FORCEPROP 1 LAST PATH I7
J 2
(900 4700);
DISPLAY 0.936170 (900 4700);
PAINT GREEN (900 4700);
DISPLAY INVISIBLE (900 4700);
FORCEADD TAP..6
R 2
(-1600 3700);
FORCEPROP 3 LASTPIN (-1650 3700) SIG_NAME M_E_DQ<38>
J 0
(-1640 3710);
DISPLAY 0.659574 (-1640 3710);
PAINT MONO (-1640 3710);
DISPLAY INVISIBLE (-1640 3710);
FORCEPROP 1 LASTPIN (-1650 3700) BN 38
J 2
(-1600 3710);
DISPLAY 0.617021 (-1600 3710);
PAINT PINK (-1600 3710);
FORCEPROP 2 LAST CDS_LIB mstr_standard
J 2
(-1600 3700);
DISPLAY 0.787234 (-1600 3700);
PAINT MONO (-1600 3700);
DISPLAY INVISIBLE (-1600 3700);
FORCEPROP 1 LAST BODY_TYPE PLUMBING
J 2
(-1600 3650);
DISPLAY 1.234043 (-1600 3650);
PAINT GREEN (-1600 3650);
DISPLAY INVISIBLE (-1600 3650);
FORCEPROP 1 LAST HDL_TAP TRUE
J 2
(-1925 3575);
DISPLAY 1.234043 (-1925 3575);
PAINT GREEN (-1925 3575);
DISPLAY INVISIBLE (-1925 3575);
FORCEPROP 1 LAST PATH I70
J 2
(-1600 3700);
DISPLAY 0.936170 (-1600 3700);
PAINT GREEN (-1600 3700);
DISPLAY INVISIBLE (-1600 3700);
FORCEADD TAP..6
R 2
(-1600 3800);
FORCEPROP 3 LASTPIN (-1650 3800) SIG_NAME M_E_DQ<40>
J 0
(-1640 3810);
DISPLAY 0.659574 (-1640 3810);
PAINT MONO (-1640 3810);
DISPLAY INVISIBLE (-1640 3810);
FORCEPROP 1 LASTPIN (-1650 3800) BN 40
J 2
(-1600 3810);
DISPLAY 0.617021 (-1600 3810);
PAINT PINK (-1600 3810);
FORCEPROP 2 LAST CDS_LIB mstr_standard
J 2
(-1600 3800);
DISPLAY 0.787234 (-1600 3800);
PAINT MONO (-1600 3800);
DISPLAY INVISIBLE (-1600 3800);
FORCEPROP 1 LAST BODY_TYPE PLUMBING
J 2
(-1600 3750);
DISPLAY 1.234043 (-1600 3750);
PAINT GREEN (-1600 3750);
DISPLAY INVISIBLE (-1600 3750);
FORCEPROP 1 LAST HDL_TAP TRUE
J 2
(-1925 3675);
DISPLAY 1.234043 (-1925 3675);
PAINT GREEN (-1925 3675);
DISPLAY INVISIBLE (-1925 3675);
FORCEPROP 1 LAST PATH I71
J 2
(-1600 3800);
DISPLAY 0.936170 (-1600 3800);
PAINT GREEN (-1600 3800);
DISPLAY INVISIBLE (-1600 3800);
FORCEADD TAP..6
R 2
(-1600 3650);
FORCEPROP 3 LASTPIN (-1650 3650) SIG_NAME M_E_DQ<39>
J 0
(-1640 3660);
DISPLAY 0.659574 (-1640 3660);
PAINT MONO (-1640 3660);
DISPLAY INVISIBLE (-1640 3660);
FORCEPROP 1 LASTPIN (-1650 3650) BN 39
J 2
(-1600 3660);
DISPLAY 0.617021 (-1600 3660);
PAINT PINK (-1600 3660);
FORCEPROP 2 LAST CDS_LIB mstr_standard
J 2
(-1600 3650);
DISPLAY 0.787234 (-1600 3650);
PAINT MONO (-1600 3650);
DISPLAY INVISIBLE (-1600 3650);
FORCEPROP 1 LAST BODY_TYPE PLUMBING
J 2
(-1600 3600);
DISPLAY 1.234043 (-1600 3600);
PAINT GREEN (-1600 3600);
DISPLAY INVISIBLE (-1600 3600);
FORCEPROP 1 LAST HDL_TAP TRUE
J 2
(-1925 3525);
DISPLAY 1.234043 (-1925 3525);
PAINT GREEN (-1925 3525);
DISPLAY INVISIBLE (-1925 3525);
FORCEPROP 1 LAST PATH I72
J 2
(-1600 3650);
DISPLAY 0.936170 (-1600 3650);
PAINT GREEN (-1600 3650);
DISPLAY INVISIBLE (-1600 3650);
FORCEADD TAP..6
R 2
(-1600 3600);
FORCEPROP 3 LASTPIN (-1650 3600) SIG_NAME M_E_DQ<36>
J 0
(-1640 3610);
DISPLAY 0.659574 (-1640 3610);
PAINT MONO (-1640 3610);
DISPLAY INVISIBLE (-1640 3610);
FORCEPROP 1 LASTPIN (-1650 3600) BN 36
J 2
(-1600 3610);
DISPLAY 0.617021 (-1600 3610);
PAINT PINK (-1600 3610);
FORCEPROP 2 LAST CDS_LIB mstr_standard
J 2
(-1600 3600);
DISPLAY 0.787234 (-1600 3600);
PAINT MONO (-1600 3600);
DISPLAY INVISIBLE (-1600 3600);
FORCEPROP 1 LAST BODY_TYPE PLUMBING
J 2
(-1600 3550);
DISPLAY 1.234043 (-1600 3550);
PAINT GREEN (-1600 3550);
DISPLAY INVISIBLE (-1600 3550);
FORCEPROP 1 LAST HDL_TAP TRUE
J 2
(-1925 3475);
DISPLAY 1.234043 (-1925 3475);
PAINT GREEN (-1925 3475);
DISPLAY INVISIBLE (-1925 3475);
FORCEPROP 1 LAST PATH I73
J 2
(-1600 3600);
DISPLAY 0.936170 (-1600 3600);
PAINT GREEN (-1600 3600);
DISPLAY INVISIBLE (-1600 3600);
FORCEADD TAP..6
R 2
(-1600 3550);
FORCEPROP 3 LASTPIN (-1650 3550) SIG_NAME M_E_DQ<37>
J 0
(-1640 3560);
DISPLAY 0.659574 (-1640 3560);
PAINT MONO (-1640 3560);
DISPLAY INVISIBLE (-1640 3560);
FORCEPROP 1 LASTPIN (-1650 3550) BN 37
J 2
(-1600 3560);
DISPLAY 0.617021 (-1600 3560);
PAINT PINK (-1600 3560);
FORCEPROP 2 LAST CDS_LIB mstr_standard
J 2
(-1600 3550);
DISPLAY 0.787234 (-1600 3550);
PAINT MONO (-1600 3550);
DISPLAY INVISIBLE (-1600 3550);
FORCEPROP 1 LAST BODY_TYPE PLUMBING
J 2
(-1600 3500);
DISPLAY 1.234043 (-1600 3500);
PAINT GREEN (-1600 3500);
DISPLAY INVISIBLE (-1600 3500);
FORCEPROP 1 LAST HDL_TAP TRUE
J 2
(-1925 3425);
DISPLAY 1.234043 (-1925 3425);
PAINT GREEN (-1925 3425);
DISPLAY INVISIBLE (-1925 3425);
FORCEPROP 1 LAST PATH I74
J 2
(-1600 3550);
DISPLAY 0.936170 (-1600 3550);
PAINT GREEN (-1600 3550);
DISPLAY INVISIBLE (-1600 3550);
FORCEADD TAP..6
R 2
(-1600 3450);
FORCEPROP 3 LASTPIN (-1650 3450) SIG_NAME M_E_DQ<35>
J 0
(-1640 3460);
DISPLAY 0.659574 (-1640 3460);
PAINT MONO (-1640 3460);
DISPLAY INVISIBLE (-1640 3460);
FORCEPROP 1 LASTPIN (-1650 3450) BN 35
J 2
(-1600 3460);
DISPLAY 0.617021 (-1600 3460);
PAINT PINK (-1600 3460);
FORCEPROP 2 LAST CDS_LIB mstr_standard
J 2
(-1600 3450);
DISPLAY 0.787234 (-1600 3450);
PAINT MONO (-1600 3450);
DISPLAY INVISIBLE (-1600 3450);
FORCEPROP 1 LAST BODY_TYPE PLUMBING
J 2
(-1600 3400);
DISPLAY 1.234043 (-1600 3400);
PAINT GREEN (-1600 3400);
DISPLAY INVISIBLE (-1600 3400);
FORCEPROP 1 LAST HDL_TAP TRUE
J 2
(-1925 3325);
DISPLAY 1.234043 (-1925 3325);
PAINT GREEN (-1925 3325);
DISPLAY INVISIBLE (-1925 3325);
FORCEPROP 1 LAST PATH I75
J 2
(-1600 3450);
DISPLAY 0.936170 (-1600 3450);
PAINT GREEN (-1600 3450);
DISPLAY INVISIBLE (-1600 3450);
FORCEADD TAP..6
R 2
(-1600 3500);
FORCEPROP 3 LASTPIN (-1650 3500) SIG_NAME M_E_DQ<34>
J 0
(-1640 3510);
DISPLAY 0.659574 (-1640 3510);
PAINT MONO (-1640 3510);
DISPLAY INVISIBLE (-1640 3510);
FORCEPROP 1 LASTPIN (-1650 3500) BN 34
J 2
(-1600 3510);
DISPLAY 0.617021 (-1600 3510);
PAINT PINK (-1600 3510);
FORCEPROP 2 LAST CDS_LIB mstr_standard
J 2
(-1600 3500);
DISPLAY 0.787234 (-1600 3500);
PAINT MONO (-1600 3500);
DISPLAY INVISIBLE (-1600 3500);
FORCEPROP 1 LAST BODY_TYPE PLUMBING
J 2
(-1600 3450);
DISPLAY 1.234043 (-1600 3450);
PAINT GREEN (-1600 3450);
DISPLAY INVISIBLE (-1600 3450);
FORCEPROP 1 LAST HDL_TAP TRUE
J 2
(-1925 3375);
DISPLAY 1.234043 (-1925 3375);
PAINT GREEN (-1925 3375);
DISPLAY INVISIBLE (-1925 3375);
FORCEPROP 1 LAST PATH I76
J 2
(-1600 3500);
DISPLAY 0.936170 (-1600 3500);
PAINT GREEN (-1600 3500);
DISPLAY INVISIBLE (-1600 3500);
FORCEADD TAP..6
R 2
(-1600 3400);
FORCEPROP 3 LASTPIN (-1650 3400) SIG_NAME M_E_DQ<32>
J 0
(-1640 3410);
DISPLAY 0.659574 (-1640 3410);
PAINT MONO (-1640 3410);
DISPLAY INVISIBLE (-1640 3410);
FORCEPROP 1 LASTPIN (-1650 3400) BN 32
J 2
(-1600 3410);
DISPLAY 0.617021 (-1600 3410);
PAINT PINK (-1600 3410);
FORCEPROP 2 LAST CDS_LIB mstr_standard
J 2
(-1600 3400);
DISPLAY 0.787234 (-1600 3400);
PAINT MONO (-1600 3400);
DISPLAY INVISIBLE (-1600 3400);
FORCEPROP 1 LAST BODY_TYPE PLUMBING
J 2
(-1600 3350);
DISPLAY 1.234043 (-1600 3350);
PAINT GREEN (-1600 3350);
DISPLAY INVISIBLE (-1600 3350);
FORCEPROP 1 LAST HDL_TAP TRUE
J 2
(-1925 3275);
DISPLAY 1.234043 (-1925 3275);
PAINT GREEN (-1925 3275);
DISPLAY INVISIBLE (-1925 3275);
FORCEPROP 1 LAST PATH I77
J 2
(-1600 3400);
DISPLAY 0.936170 (-1600 3400);
PAINT GREEN (-1600 3400);
DISPLAY INVISIBLE (-1600 3400);
FORCEADD TAP..6
R 2
(-1600 3350);
FORCEPROP 3 LASTPIN (-1650 3350) SIG_NAME M_E_DQ<33>
J 0
(-1640 3360);
DISPLAY 0.659574 (-1640 3360);
PAINT MONO (-1640 3360);
DISPLAY INVISIBLE (-1640 3360);
FORCEPROP 1 LASTPIN (-1650 3350) BN 33
J 2
(-1600 3360);
DISPLAY 0.617021 (-1600 3360);
PAINT PINK (-1600 3360);
FORCEPROP 2 LAST CDS_LIB mstr_standard
J 2
(-1600 3350);
DISPLAY 0.787234 (-1600 3350);
PAINT MONO (-1600 3350);
DISPLAY INVISIBLE (-1600 3350);
FORCEPROP 1 LAST BODY_TYPE PLUMBING
J 2
(-1600 3300);
DISPLAY 1.234043 (-1600 3300);
PAINT GREEN (-1600 3300);
DISPLAY INVISIBLE (-1600 3300);
FORCEPROP 1 LAST HDL_TAP TRUE
J 2
(-1925 3225);
DISPLAY 1.234043 (-1925 3225);
PAINT GREEN (-1925 3225);
DISPLAY INVISIBLE (-1925 3225);
FORCEPROP 1 LAST PATH I78
J 2
(-1600 3350);
DISPLAY 0.936170 (-1600 3350);
PAINT GREEN (-1600 3350);
DISPLAY INVISIBLE (-1600 3350);
FORCEADD TAP..6
R 2
(-1600 3200);
FORCEPROP 3 LASTPIN (-1650 3200) SIG_NAME M_E_DQ<28>
J 0
(-1640 3210);
DISPLAY 0.659574 (-1640 3210);
PAINT MONO (-1640 3210);
DISPLAY INVISIBLE (-1640 3210);
FORCEPROP 1 LASTPIN (-1650 3200) BN 28
J 2
(-1600 3210);
DISPLAY 0.617021 (-1600 3210);
PAINT PINK (-1600 3210);
FORCEPROP 2 LAST CDS_LIB mstr_standard
J 2
(-1600 3200);
DISPLAY 0.787234 (-1600 3200);
PAINT MONO (-1600 3200);
DISPLAY INVISIBLE (-1600 3200);
FORCEPROP 1 LAST BODY_TYPE PLUMBING
J 2
(-1600 3150);
DISPLAY 1.234043 (-1600 3150);
PAINT GREEN (-1600 3150);
DISPLAY INVISIBLE (-1600 3150);
FORCEPROP 1 LAST HDL_TAP TRUE
J 2
(-1925 3075);
DISPLAY 1.234043 (-1925 3075);
PAINT GREEN (-1925 3075);
DISPLAY INVISIBLE (-1925 3075);
FORCEPROP 1 LAST PATH I79
J 2
(-1600 3200);
DISPLAY 0.936170 (-1600 3200);
PAINT GREEN (-1600 3200);
DISPLAY INVISIBLE (-1600 3200);
FORCEADD TAP..6
R 2
(900 4800);
FORCEPROP 3 LASTPIN (850 4800) SIG_NAME M_E_DQS_DN<14>
J 0
(860 4810);
DISPLAY 0.659574 (860 4810);
PAINT MONO (860 4810);
DISPLAY INVISIBLE (860 4810);
FORCEPROP 1 LASTPIN (850 4800) BN 14
J 2
(900 4810);
DISPLAY 0.617021 (900 4810);
PAINT PINK (900 4810);
FORCEPROP 2 LAST CDS_LIB mstr_standard
J 0
(900 4800);
DISPLAY 0.787234 (900 4800);
PAINT MONO (900 4800);
DISPLAY INVISIBLE (900 4800);
FORCEPROP 1 LAST BODY_TYPE PLUMBING
J 2
(900 4750);
DISPLAY 1.234043 (900 4750);
PAINT GREEN (900 4750);
DISPLAY INVISIBLE (900 4750);
FORCEPROP 1 LAST HDL_TAP TRUE
J 2
(575 4675);
DISPLAY 1.234043 (575 4675);
PAINT GREEN (575 4675);
DISPLAY INVISIBLE (575 4675);
FORCEPROP 1 LAST PATH I8
J 2
(900 4800);
DISPLAY 0.936170 (900 4800);
PAINT GREEN (900 4800);
DISPLAY INVISIBLE (900 4800);
FORCEADD TAP..6
R 2
(-1600 3300);
FORCEPROP 3 LASTPIN (-1650 3300) SIG_NAME M_E_DQ<30>
J 0
(-1640 3310);
DISPLAY 0.659574 (-1640 3310);
PAINT MONO (-1640 3310);
DISPLAY INVISIBLE (-1640 3310);
FORCEPROP 1 LASTPIN (-1650 3300) BN 30
J 2
(-1600 3310);
DISPLAY 0.617021 (-1600 3310);
PAINT PINK (-1600 3310);
FORCEPROP 2 LAST CDS_LIB mstr_standard
J 2
(-1600 3300);
DISPLAY 0.787234 (-1600 3300);
PAINT MONO (-1600 3300);
DISPLAY INVISIBLE (-1600 3300);
FORCEPROP 1 LAST BODY_TYPE PLUMBING
J 2
(-1600 3250);
DISPLAY 1.234043 (-1600 3250);
PAINT GREEN (-1600 3250);
DISPLAY INVISIBLE (-1600 3250);
FORCEPROP 1 LAST HDL_TAP TRUE
J 2
(-1925 3175);
DISPLAY 1.234043 (-1925 3175);
PAINT GREEN (-1925 3175);
DISPLAY INVISIBLE (-1925 3175);
FORCEPROP 1 LAST PATH I80
J 2
(-1600 3300);
DISPLAY 0.936170 (-1600 3300);
PAINT GREEN (-1600 3300);
DISPLAY INVISIBLE (-1600 3300);
FORCEADD TAP..6
R 2
(-1600 3250);
FORCEPROP 3 LASTPIN (-1650 3250) SIG_NAME M_E_DQ<31>
J 0
(-1640 3260);
DISPLAY 0.659574 (-1640 3260);
PAINT MONO (-1640 3260);
DISPLAY INVISIBLE (-1640 3260);
FORCEPROP 1 LASTPIN (-1650 3250) BN 31
J 2
(-1600 3260);
DISPLAY 0.617021 (-1600 3260);
PAINT PINK (-1600 3260);
FORCEPROP 2 LAST CDS_LIB mstr_standard
J 2
(-1600 3250);
DISPLAY 0.787234 (-1600 3250);
PAINT MONO (-1600 3250);
DISPLAY INVISIBLE (-1600 3250);
FORCEPROP 1 LAST BODY_TYPE PLUMBING
J 2
(-1600 3200);
DISPLAY 1.234043 (-1600 3200);
PAINT GREEN (-1600 3200);
DISPLAY INVISIBLE (-1600 3200);
FORCEPROP 1 LAST HDL_TAP TRUE
J 2
(-1925 3125);
DISPLAY 1.234043 (-1925 3125);
PAINT GREEN (-1925 3125);
DISPLAY INVISIBLE (-1925 3125);
FORCEPROP 1 LAST PATH I81
J 2
(-1600 3250);
DISPLAY 0.936170 (-1600 3250);
PAINT GREEN (-1600 3250);
DISPLAY INVISIBLE (-1600 3250);
FORCEADD TAP..6
R 2
(-1600 3100);
FORCEPROP 3 LASTPIN (-1650 3100) SIG_NAME M_E_DQ<26>
J 0
(-1640 3110);
DISPLAY 0.659574 (-1640 3110);
PAINT MONO (-1640 3110);
DISPLAY INVISIBLE (-1640 3110);
FORCEPROP 1 LASTPIN (-1650 3100) BN 26
J 2
(-1600 3110);
DISPLAY 0.617021 (-1600 3110);
PAINT PINK (-1600 3110);
FORCEPROP 2 LAST CDS_LIB mstr_standard
J 2
(-1600 3100);
DISPLAY 0.787234 (-1600 3100);
PAINT MONO (-1600 3100);
DISPLAY INVISIBLE (-1600 3100);
FORCEPROP 1 LAST BODY_TYPE PLUMBING
J 2
(-1600 3050);
DISPLAY 1.234043 (-1600 3050);
PAINT GREEN (-1600 3050);
DISPLAY INVISIBLE (-1600 3050);
FORCEPROP 1 LAST HDL_TAP TRUE
J 2
(-1925 2975);
DISPLAY 1.234043 (-1925 2975);
PAINT GREEN (-1925 2975);
DISPLAY INVISIBLE (-1925 2975);
FORCEPROP 1 LAST PATH I82
J 2
(-1600 3100);
DISPLAY 0.936170 (-1600 3100);
PAINT GREEN (-1600 3100);
DISPLAY INVISIBLE (-1600 3100);
FORCEADD TAP..6
R 2
(-1600 3150);
FORCEPROP 3 LASTPIN (-1650 3150) SIG_NAME M_E_DQ<29>
J 0
(-1640 3160);
DISPLAY 0.659574 (-1640 3160);
PAINT MONO (-1640 3160);
DISPLAY INVISIBLE (-1640 3160);
FORCEPROP 1 LASTPIN (-1650 3150) BN 29
J 2
(-1600 3160);
DISPLAY 0.617021 (-1600 3160);
PAINT PINK (-1600 3160);
FORCEPROP 2 LAST CDS_LIB mstr_standard
J 2
(-1600 3150);
DISPLAY 0.787234 (-1600 3150);
PAINT MONO (-1600 3150);
DISPLAY INVISIBLE (-1600 3150);
FORCEPROP 1 LAST BODY_TYPE PLUMBING
J 2
(-1600 3100);
DISPLAY 1.234043 (-1600 3100);
PAINT GREEN (-1600 3100);
DISPLAY INVISIBLE (-1600 3100);
FORCEPROP 1 LAST HDL_TAP TRUE
J 2
(-1925 3025);
DISPLAY 1.234043 (-1925 3025);
PAINT GREEN (-1925 3025);
DISPLAY INVISIBLE (-1925 3025);
FORCEPROP 1 LAST PATH I83
J 2
(-1600 3150);
DISPLAY 0.936170 (-1600 3150);
PAINT GREEN (-1600 3150);
DISPLAY INVISIBLE (-1600 3150);
FORCEADD TAP..6
R 2
(-1600 3050);
FORCEPROP 3 LASTPIN (-1650 3050) SIG_NAME M_E_DQ<27>
J 0
(-1640 3060);
DISPLAY 0.659574 (-1640 3060);
PAINT MONO (-1640 3060);
DISPLAY INVISIBLE (-1640 3060);
FORCEPROP 1 LASTPIN (-1650 3050) BN 27
J 2
(-1600 3060);
DISPLAY 0.617021 (-1600 3060);
PAINT PINK (-1600 3060);
FORCEPROP 2 LAST CDS_LIB mstr_standard
J 2
(-1600 3050);
DISPLAY 0.787234 (-1600 3050);
PAINT MONO (-1600 3050);
DISPLAY INVISIBLE (-1600 3050);
FORCEPROP 1 LAST BODY_TYPE PLUMBING
J 2
(-1600 3000);
DISPLAY 1.234043 (-1600 3000);
PAINT GREEN (-1600 3000);
DISPLAY INVISIBLE (-1600 3000);
FORCEPROP 1 LAST HDL_TAP TRUE
J 2
(-1925 2925);
DISPLAY 1.234043 (-1925 2925);
PAINT GREEN (-1925 2925);
DISPLAY INVISIBLE (-1925 2925);
FORCEPROP 1 LAST PATH I84
J 2
(-1600 3050);
DISPLAY 0.936170 (-1600 3050);
PAINT GREEN (-1600 3050);
DISPLAY INVISIBLE (-1600 3050);
FORCEADD TAP..6
R 2
(-1600 2950);
FORCEPROP 3 LASTPIN (-1650 2950) SIG_NAME M_E_DQ<25>
J 0
(-1640 2960);
DISPLAY 0.659574 (-1640 2960);
PAINT MONO (-1640 2960);
DISPLAY INVISIBLE (-1640 2960);
FORCEPROP 1 LASTPIN (-1650 2950) BN 25
J 2
(-1600 2960);
DISPLAY 0.617021 (-1600 2960);
PAINT PINK (-1600 2960);
FORCEPROP 2 LAST CDS_LIB mstr_standard
J 2
(-1600 2950);
DISPLAY 0.787234 (-1600 2950);
PAINT MONO (-1600 2950);
DISPLAY INVISIBLE (-1600 2950);
FORCEPROP 1 LAST BODY_TYPE PLUMBING
J 2
(-1600 2900);
DISPLAY 1.234043 (-1600 2900);
PAINT GREEN (-1600 2900);
DISPLAY INVISIBLE (-1600 2900);
FORCEPROP 1 LAST HDL_TAP TRUE
J 2
(-1925 2825);
DISPLAY 1.234043 (-1925 2825);
PAINT GREEN (-1925 2825);
DISPLAY INVISIBLE (-1925 2825);
FORCEPROP 1 LAST PATH I85
J 2
(-1600 2950);
DISPLAY 0.936170 (-1600 2950);
PAINT GREEN (-1600 2950);
DISPLAY INVISIBLE (-1600 2950);
FORCEADD TAP..6
R 2
(-1600 3000);
FORCEPROP 3 LASTPIN (-1650 3000) SIG_NAME M_E_DQ<24>
J 0
(-1640 3010);
DISPLAY 0.659574 (-1640 3010);
PAINT MONO (-1640 3010);
DISPLAY INVISIBLE (-1640 3010);
FORCEPROP 1 LASTPIN (-1650 3000) BN 24
J 2
(-1600 3010);
DISPLAY 0.617021 (-1600 3010);
PAINT PINK (-1600 3010);
FORCEPROP 2 LAST CDS_LIB mstr_standard
J 2
(-1600 3000);
DISPLAY 0.787234 (-1600 3000);
PAINT MONO (-1600 3000);
DISPLAY INVISIBLE (-1600 3000);
FORCEPROP 1 LAST BODY_TYPE PLUMBING
J 2
(-1600 2950);
DISPLAY 1.234043 (-1600 2950);
PAINT GREEN (-1600 2950);
DISPLAY INVISIBLE (-1600 2950);
FORCEPROP 1 LAST HDL_TAP TRUE
J 2
(-1925 2875);
DISPLAY 1.234043 (-1925 2875);
PAINT GREEN (-1925 2875);
DISPLAY INVISIBLE (-1925 2875);
FORCEPROP 1 LAST PATH I86
J 2
(-1600 3000);
DISPLAY 0.936170 (-1600 3000);
PAINT GREEN (-1600 3000);
DISPLAY INVISIBLE (-1600 3000);
FORCEADD TAP..6
R 2
(-1600 2850);
FORCEPROP 3 LASTPIN (-1650 2850) SIG_NAME M_E_DQ<23>
J 0
(-1640 2860);
DISPLAY 0.659574 (-1640 2860);
PAINT MONO (-1640 2860);
DISPLAY INVISIBLE (-1640 2860);
FORCEPROP 1 LASTPIN (-1650 2850) BN 23
J 2
(-1600 2860);
DISPLAY 0.617021 (-1600 2860);
PAINT PINK (-1600 2860);
FORCEPROP 2 LAST CDS_LIB mstr_standard
J 2
(-1600 2850);
DISPLAY 0.787234 (-1600 2850);
PAINT MONO (-1600 2850);
DISPLAY INVISIBLE (-1600 2850);
FORCEPROP 1 LAST BODY_TYPE PLUMBING
J 2
(-1600 2800);
DISPLAY 1.234043 (-1600 2800);
PAINT GREEN (-1600 2800);
DISPLAY INVISIBLE (-1600 2800);
FORCEPROP 1 LAST HDL_TAP TRUE
J 2
(-1925 2725);
DISPLAY 1.234043 (-1925 2725);
PAINT GREEN (-1925 2725);
DISPLAY INVISIBLE (-1925 2725);
FORCEPROP 1 LAST PATH I87
J 2
(-1600 2850);
DISPLAY 0.936170 (-1600 2850);
PAINT GREEN (-1600 2850);
DISPLAY INVISIBLE (-1600 2850);
FORCEADD TAP..6
R 2
(-1600 2900);
FORCEPROP 3 LASTPIN (-1650 2900) SIG_NAME M_E_DQ<22>
J 0
(-1640 2910);
DISPLAY 0.659574 (-1640 2910);
PAINT MONO (-1640 2910);
DISPLAY INVISIBLE (-1640 2910);
FORCEPROP 1 LASTPIN (-1650 2900) BN 22
J 2
(-1600 2910);
DISPLAY 0.617021 (-1600 2910);
PAINT PINK (-1600 2910);
FORCEPROP 2 LAST CDS_LIB mstr_standard
J 2
(-1600 2900);
DISPLAY 0.787234 (-1600 2900);
PAINT MONO (-1600 2900);
DISPLAY INVISIBLE (-1600 2900);
FORCEPROP 1 LAST BODY_TYPE PLUMBING
J 2
(-1600 2850);
DISPLAY 1.234043 (-1600 2850);
PAINT GREEN (-1600 2850);
DISPLAY INVISIBLE (-1600 2850);
FORCEPROP 1 LAST HDL_TAP TRUE
J 2
(-1925 2775);
DISPLAY 1.234043 (-1925 2775);
PAINT GREEN (-1925 2775);
DISPLAY INVISIBLE (-1925 2775);
FORCEPROP 1 LAST PATH I88
J 2
(-1600 2900);
DISPLAY 0.936170 (-1600 2900);
PAINT GREEN (-1600 2900);
DISPLAY INVISIBLE (-1600 2900);
FORCEADD TAP..6
R 2
(-1600 2800);
FORCEPROP 3 LASTPIN (-1650 2800) SIG_NAME M_E_DQ<20>
J 0
(-1640 2810);
DISPLAY 0.659574 (-1640 2810);
PAINT MONO (-1640 2810);
DISPLAY INVISIBLE (-1640 2810);
FORCEPROP 1 LASTPIN (-1650 2800) BN 20
J 2
(-1600 2810);
DISPLAY 0.617021 (-1600 2810);
PAINT PINK (-1600 2810);
FORCEPROP 2 LAST CDS_LIB mstr_standard
J 2
(-1600 2800);
DISPLAY 0.787234 (-1600 2800);
PAINT MONO (-1600 2800);
DISPLAY INVISIBLE (-1600 2800);
FORCEPROP 1 LAST BODY_TYPE PLUMBING
J 2
(-1600 2750);
DISPLAY 1.234043 (-1600 2750);
PAINT GREEN (-1600 2750);
DISPLAY INVISIBLE (-1600 2750);
FORCEPROP 1 LAST HDL_TAP TRUE
J 2
(-1925 2675);
DISPLAY 1.234043 (-1925 2675);
PAINT GREEN (-1925 2675);
DISPLAY INVISIBLE (-1925 2675);
FORCEPROP 1 LAST PATH I89
J 2
(-1600 2800);
DISPLAY 0.936170 (-1600 2800);
PAINT GREEN (-1600 2800);
DISPLAY INVISIBLE (-1600 2800);
FORCEADD TAP..6
R 2
(900 4600);
FORCEPROP 3 LASTPIN (850 4600) SIG_NAME M_E_DQS_DN<12>
J 0
(860 4610);
DISPLAY 0.659574 (860 4610);
PAINT MONO (860 4610);
DISPLAY INVISIBLE (860 4610);
FORCEPROP 1 LASTPIN (850 4600) BN 12
J 2
(900 4610);
DISPLAY 0.617021 (900 4610);
PAINT PINK (900 4610);
FORCEPROP 2 LAST CDS_LIB mstr_standard
J 0
(900 4600);
DISPLAY 0.787234 (900 4600);
PAINT MONO (900 4600);
DISPLAY INVISIBLE (900 4600);
FORCEPROP 1 LAST BODY_TYPE PLUMBING
J 2
(900 4550);
DISPLAY 1.234043 (900 4550);
PAINT GREEN (900 4550);
DISPLAY INVISIBLE (900 4550);
FORCEPROP 1 LAST HDL_TAP TRUE
J 2
(575 4475);
DISPLAY 1.234043 (575 4475);
PAINT GREEN (575 4475);
DISPLAY INVISIBLE (575 4475);
FORCEPROP 1 LAST PATH I9
J 2
(900 4600);
DISPLAY 0.936170 (900 4600);
PAINT GREEN (900 4600);
DISPLAY INVISIBLE (900 4600);
FORCEADD TAP..6
R 2
(-1600 2750);
FORCEPROP 3 LASTPIN (-1650 2750) SIG_NAME M_E_DQ<21>
J 0
(-1640 2760);
DISPLAY 0.659574 (-1640 2760);
PAINT MONO (-1640 2760);
DISPLAY INVISIBLE (-1640 2760);
FORCEPROP 1 LASTPIN (-1650 2750) BN 21
J 2
(-1600 2760);
DISPLAY 0.617021 (-1600 2760);
PAINT PINK (-1600 2760);
FORCEPROP 2 LAST CDS_LIB mstr_standard
J 2
(-1600 2750);
DISPLAY 0.787234 (-1600 2750);
PAINT MONO (-1600 2750);
DISPLAY INVISIBLE (-1600 2750);
FORCEPROP 1 LAST BODY_TYPE PLUMBING
J 2
(-1600 2700);
DISPLAY 1.234043 (-1600 2700);
PAINT GREEN (-1600 2700);
DISPLAY INVISIBLE (-1600 2700);
FORCEPROP 1 LAST HDL_TAP TRUE
J 2
(-1925 2625);
DISPLAY 1.234043 (-1925 2625);
PAINT GREEN (-1925 2625);
DISPLAY INVISIBLE (-1925 2625);
FORCEPROP 1 LAST PATH I90
J 2
(-1600 2750);
DISPLAY 0.936170 (-1600 2750);
PAINT GREEN (-1600 2750);
DISPLAY INVISIBLE (-1600 2750);
FORCEADD TAP..6
R 2
(-1600 2700);
FORCEPROP 3 LASTPIN (-1650 2700) SIG_NAME M_E_DQ<18>
J 0
(-1640 2710);
DISPLAY 0.659574 (-1640 2710);
PAINT MONO (-1640 2710);
DISPLAY INVISIBLE (-1640 2710);
FORCEPROP 1 LASTPIN (-1650 2700) BN 18
J 2
(-1600 2710);
DISPLAY 0.617021 (-1600 2710);
PAINT PINK (-1600 2710);
FORCEPROP 2 LAST CDS_LIB mstr_standard
J 2
(-1600 2700);
DISPLAY 0.787234 (-1600 2700);
PAINT MONO (-1600 2700);
DISPLAY INVISIBLE (-1600 2700);
FORCEPROP 1 LAST BODY_TYPE PLUMBING
J 2
(-1600 2650);
DISPLAY 1.234043 (-1600 2650);
PAINT GREEN (-1600 2650);
DISPLAY INVISIBLE (-1600 2650);
FORCEPROP 1 LAST HDL_TAP TRUE
J 2
(-1925 2575);
DISPLAY 1.234043 (-1925 2575);
PAINT GREEN (-1925 2575);
DISPLAY INVISIBLE (-1925 2575);
FORCEPROP 1 LAST PATH I91
J 2
(-1600 2700);
DISPLAY 0.936170 (-1600 2700);
PAINT GREEN (-1600 2700);
DISPLAY INVISIBLE (-1600 2700);
FORCEADD TAP..6
R 2
(-1600 2650);
FORCEPROP 3 LASTPIN (-1650 2650) SIG_NAME M_E_DQ<19>
J 0
(-1640 2660);
DISPLAY 0.659574 (-1640 2660);
PAINT MONO (-1640 2660);
DISPLAY INVISIBLE (-1640 2660);
FORCEPROP 1 LASTPIN (-1650 2650) BN 19
J 2
(-1600 2660);
DISPLAY 0.617021 (-1600 2660);
PAINT PINK (-1600 2660);
FORCEPROP 2 LAST CDS_LIB mstr_standard
J 2
(-1600 2650);
DISPLAY 0.787234 (-1600 2650);
PAINT MONO (-1600 2650);
DISPLAY INVISIBLE (-1600 2650);
FORCEPROP 1 LAST BODY_TYPE PLUMBING
J 2
(-1600 2600);
DISPLAY 1.234043 (-1600 2600);
PAINT GREEN (-1600 2600);
DISPLAY INVISIBLE (-1600 2600);
FORCEPROP 1 LAST HDL_TAP TRUE
J 2
(-1925 2525);
DISPLAY 1.234043 (-1925 2525);
PAINT GREEN (-1925 2525);
DISPLAY INVISIBLE (-1925 2525);
FORCEPROP 1 LAST PATH I92
J 2
(-1600 2650);
DISPLAY 0.936170 (-1600 2650);
PAINT GREEN (-1600 2650);
DISPLAY INVISIBLE (-1600 2650);
FORCEADD TAP..6
R 2
(-1600 2550);
FORCEPROP 3 LASTPIN (-1650 2550) SIG_NAME M_E_DQ<17>
J 0
(-1640 2560);
DISPLAY 0.659574 (-1640 2560);
PAINT MONO (-1640 2560);
DISPLAY INVISIBLE (-1640 2560);
FORCEPROP 1 LASTPIN (-1650 2550) BN 17
J 2
(-1600 2560);
DISPLAY 0.617021 (-1600 2560);
PAINT PINK (-1600 2560);
FORCEPROP 2 LAST CDS_LIB mstr_standard
J 2
(-1600 2550);
DISPLAY 0.787234 (-1600 2550);
PAINT MONO (-1600 2550);
DISPLAY INVISIBLE (-1600 2550);
FORCEPROP 1 LAST BODY_TYPE PLUMBING
J 2
(-1600 2500);
DISPLAY 1.234043 (-1600 2500);
PAINT GREEN (-1600 2500);
DISPLAY INVISIBLE (-1600 2500);
FORCEPROP 1 LAST HDL_TAP TRUE
J 2
(-1925 2425);
DISPLAY 1.234043 (-1925 2425);
PAINT GREEN (-1925 2425);
DISPLAY INVISIBLE (-1925 2425);
FORCEPROP 1 LAST PATH I93
J 2
(-1600 2550);
DISPLAY 0.936170 (-1600 2550);
PAINT GREEN (-1600 2550);
DISPLAY INVISIBLE (-1600 2550);
FORCEADD TAP..6
R 2
(-1600 2600);
FORCEPROP 3 LASTPIN (-1650 2600) SIG_NAME M_E_DQ<16>
J 0
(-1640 2610);
DISPLAY 0.659574 (-1640 2610);
PAINT MONO (-1640 2610);
DISPLAY INVISIBLE (-1640 2610);
FORCEPROP 1 LASTPIN (-1650 2600) BN 16
J 2
(-1600 2610);
DISPLAY 0.617021 (-1600 2610);
PAINT PINK (-1600 2610);
FORCEPROP 2 LAST CDS_LIB mstr_standard
J 2
(-1600 2600);
DISPLAY 0.787234 (-1600 2600);
PAINT MONO (-1600 2600);
DISPLAY INVISIBLE (-1600 2600);
FORCEPROP 1 LAST BODY_TYPE PLUMBING
J 2
(-1600 2550);
DISPLAY 1.234043 (-1600 2550);
PAINT GREEN (-1600 2550);
DISPLAY INVISIBLE (-1600 2550);
FORCEPROP 1 LAST HDL_TAP TRUE
J 2
(-1925 2475);
DISPLAY 1.234043 (-1925 2475);
PAINT GREEN (-1925 2475);
DISPLAY INVISIBLE (-1925 2475);
FORCEPROP 1 LAST PATH I94
J 2
(-1600 2600);
DISPLAY 0.936170 (-1600 2600);
PAINT GREEN (-1600 2600);
DISPLAY INVISIBLE (-1600 2600);
FORCEADD TAP..6
R 2
(-1600 2500);
FORCEPROP 3 LASTPIN (-1650 2500) SIG_NAME M_E_DQ<14>
J 0
(-1640 2510);
DISPLAY 0.659574 (-1640 2510);
PAINT MONO (-1640 2510);
DISPLAY INVISIBLE (-1640 2510);
FORCEPROP 1 LASTPIN (-1650 2500) BN 14
J 2
(-1600 2510);
DISPLAY 0.617021 (-1600 2510);
PAINT PINK (-1600 2510);
FORCEPROP 2 LAST CDS_LIB mstr_standard
J 2
(-1600 2500);
DISPLAY 0.787234 (-1600 2500);
PAINT MONO (-1600 2500);
DISPLAY INVISIBLE (-1600 2500);
FORCEPROP 1 LAST BODY_TYPE PLUMBING
J 2
(-1600 2450);
DISPLAY 1.234043 (-1600 2450);
PAINT GREEN (-1600 2450);
DISPLAY INVISIBLE (-1600 2450);
FORCEPROP 1 LAST HDL_TAP TRUE
J 2
(-1925 2375);
DISPLAY 1.234043 (-1925 2375);
PAINT GREEN (-1925 2375);
DISPLAY INVISIBLE (-1925 2375);
FORCEPROP 1 LAST PATH I95
J 2
(-1600 2500);
DISPLAY 0.936170 (-1600 2500);
PAINT GREEN (-1600 2500);
DISPLAY INVISIBLE (-1600 2500);
FORCEADD TAP..6
R 2
(-1600 2450);
FORCEPROP 3 LASTPIN (-1650 2450) SIG_NAME M_E_DQ<15>
J 0
(-1640 2460);
DISPLAY 0.659574 (-1640 2460);
PAINT MONO (-1640 2460);
DISPLAY INVISIBLE (-1640 2460);
FORCEPROP 1 LASTPIN (-1650 2450) BN 15
J 2
(-1600 2460);
DISPLAY 0.617021 (-1600 2460);
PAINT PINK (-1600 2460);
FORCEPROP 2 LAST CDS_LIB mstr_standard
J 2
(-1600 2450);
DISPLAY 0.787234 (-1600 2450);
PAINT MONO (-1600 2450);
DISPLAY INVISIBLE (-1600 2450);
FORCEPROP 1 LAST BODY_TYPE PLUMBING
J 2
(-1600 2400);
DISPLAY 1.234043 (-1600 2400);
PAINT GREEN (-1600 2400);
DISPLAY INVISIBLE (-1600 2400);
FORCEPROP 1 LAST HDL_TAP TRUE
J 2
(-1925 2325);
DISPLAY 1.234043 (-1925 2325);
PAINT GREEN (-1925 2325);
DISPLAY INVISIBLE (-1925 2325);
FORCEPROP 1 LAST PATH I96
J 2
(-1600 2450);
DISPLAY 0.936170 (-1600 2450);
PAINT GREEN (-1600 2450);
DISPLAY INVISIBLE (-1600 2450);
FORCEADD TAP..6
R 2
(-1600 2350);
FORCEPROP 3 LASTPIN (-1650 2350) SIG_NAME M_E_DQ<13>
J 0
(-1640 2360);
DISPLAY 0.659574 (-1640 2360);
PAINT MONO (-1640 2360);
DISPLAY INVISIBLE (-1640 2360);
FORCEPROP 1 LASTPIN (-1650 2350) BN 13
J 2
(-1600 2360);
DISPLAY 0.617021 (-1600 2360);
PAINT PINK (-1600 2360);
FORCEPROP 2 LAST CDS_LIB mstr_standard
J 2
(-1600 2350);
DISPLAY 0.787234 (-1600 2350);
PAINT MONO (-1600 2350);
DISPLAY INVISIBLE (-1600 2350);
FORCEPROP 1 LAST BODY_TYPE PLUMBING
J 2
(-1600 2300);
DISPLAY 1.234043 (-1600 2300);
PAINT GREEN (-1600 2300);
DISPLAY INVISIBLE (-1600 2300);
FORCEPROP 1 LAST HDL_TAP TRUE
J 2
(-1925 2225);
DISPLAY 1.234043 (-1925 2225);
PAINT GREEN (-1925 2225);
DISPLAY INVISIBLE (-1925 2225);
FORCEPROP 1 LAST PATH I97
J 2
(-1600 2350);
DISPLAY 0.936170 (-1600 2350);
PAINT GREEN (-1600 2350);
DISPLAY INVISIBLE (-1600 2350);
FORCEADD TAP..6
R 2
(-1600 2400);
FORCEPROP 3 LASTPIN (-1650 2400) SIG_NAME M_E_DQ<12>
J 0
(-1640 2410);
DISPLAY 0.659574 (-1640 2410);
PAINT MONO (-1640 2410);
DISPLAY INVISIBLE (-1640 2410);
FORCEPROP 1 LASTPIN (-1650 2400) BN 12
J 2
(-1600 2410);
DISPLAY 0.617021 (-1600 2410);
PAINT PINK (-1600 2410);
FORCEPROP 2 LAST CDS_LIB mstr_standard
J 2
(-1600 2400);
DISPLAY 0.787234 (-1600 2400);
PAINT MONO (-1600 2400);
DISPLAY INVISIBLE (-1600 2400);
FORCEPROP 1 LAST BODY_TYPE PLUMBING
J 2
(-1600 2350);
DISPLAY 1.234043 (-1600 2350);
PAINT GREEN (-1600 2350);
DISPLAY INVISIBLE (-1600 2350);
FORCEPROP 1 LAST HDL_TAP TRUE
J 2
(-1925 2275);
DISPLAY 1.234043 (-1925 2275);
PAINT GREEN (-1925 2275);
DISPLAY INVISIBLE (-1925 2275);
FORCEPROP 1 LAST PATH I98
J 2
(-1600 2400);
DISPLAY 0.936170 (-1600 2400);
PAINT GREEN (-1600 2400);
DISPLAY INVISIBLE (-1600 2400);
FORCEADD TAP..6
R 2
(-1600 2300);
FORCEPROP 3 LASTPIN (-1650 2300) SIG_NAME M_E_DQ<10>
J 0
(-1640 2310);
DISPLAY 0.659574 (-1640 2310);
PAINT MONO (-1640 2310);
DISPLAY INVISIBLE (-1640 2310);
FORCEPROP 1 LASTPIN (-1650 2300) BN 10
J 2
(-1600 2310);
DISPLAY 0.617021 (-1600 2310);
PAINT PINK (-1600 2310);
FORCEPROP 2 LAST CDS_LIB mstr_standard
J 2
(-1600 2300);
DISPLAY 0.787234 (-1600 2300);
PAINT MONO (-1600 2300);
DISPLAY INVISIBLE (-1600 2300);
FORCEPROP 1 LAST BODY_TYPE PLUMBING
J 2
(-1600 2250);
DISPLAY 1.234043 (-1600 2250);
PAINT GREEN (-1600 2250);
DISPLAY INVISIBLE (-1600 2250);
FORCEPROP 1 LAST HDL_TAP TRUE
J 2
(-1925 2175);
DISPLAY 1.234043 (-1925 2175);
PAINT GREEN (-1925 2175);
DISPLAY INVISIBLE (-1925 2175);
FORCEPROP 1 LAST PATH I99
J 2
(-1600 2300);
DISPLAY 0.936170 (-1600 2300);
PAINT GREEN (-1600 2300);
DISPLAY INVISIBLE (-1600 2300);
FORCEADD BOM_NOTE..1
(-5025 5300);
FORCEPROP 0 LAST L1 STUFF FOR SKU A & B
J 0
(-5175 5200);
DISPLAY 1.063830 (-5175 5200);
PAINT WHITE (-5175 5200);
FORCEPROP 2 LAST BOM_COST SB
J 0
(-5175 5275);
DISPLAY 1.361702 (-5175 5275);
PAINT ORANGE (-5175 5275);
DISPLAY INVISIBLE (-5175 5275);
FORCEPROP 2 LAST CDS_LIB mstr_symbols
J 0
(-5025 5300);
PAINT ORANGE (-5025 5300);
DISPLAY INVISIBLE (-5025 5300);
FORCEPROP 1 LAST COMMENT_BODY TRUE
J 0
(-5000 5400);
DISPLAY 1.319149 (-5000 5400);
PAINT ORANGE (-5000 5400);
DISPLAY INVISIBLE (-5000 5400);
FORCEPROP 2 LAST ROOM SB_HEADERS
J 0
(-5175 5275);
DISPLAY 1.361702 (-5175 5275);
PAINT ORANGE (-5175 5275);
DISPLAY INVISIBLE (-5175 5275);
FORCEADD INTEL_CORP_BPAGE..1
(2650 500);
FORCEPROP 1 LAST CDS_CON_LAST_MODIFIED Tue Dec 01 11:51:30 2015
J 0
(1225 825);
DISPLAY 0.787234 (1225 825);
PAINT ORANGE (1225 825);
DISPLAY INVISIBLE (1225 825);
FORCEPROP 1 LAST CUSTOM_TXT_CDS <CURRENT_DESIGN_SHEET> OF <TOTAL_DESIGN_SHEETS>
J 0
(2150 525);
PAINT GREEN (2150 525);
FORCEPROP 1 LAST CUSTOM_TXT_CDS <CON_LAST_MODIFIED>
J 0
(725 850);
PAINT GREEN (725 850);
FORCEPROP 2 LAST CUSTOM_TXT_CDS <XR_PAGE_TITLE>
J 0
(-5240 5750);
DISPLAY 0.638298 (-5240 5750);
PAINT PINK (-5240 5750);
DISPLAY INVISIBLE (-5240 5750);
FORCEPROP 1 LAST SCH_ADDRESS3 Santa Clara, CA 95052-8119
J 0
(-1325 525);
DISPLAY 0.617021 (-1325 525);
PAINT GREEN (-1325 525);
FORCEPROP 1 LAST SCH_ADDRESS2 P.O. BOX 58119
J 0
(-1325 575);
DISPLAY 0.617021 (-1325 575);
PAINT GREEN (-1325 575);
FORCEPROP 1 LAST SCH_ADDRESS1 2200 Mission College Blvd.
J 0
(-1325 625);
DISPLAY 0.617021 (-1325 625);
PAINT GREEN (-1325 625);
FORCEPROP 1 LAST SCH_TITLE CPU0 DDR4 CH E DIMM0
J 0
(-5300 550);
DISPLAY 1.212766 (-5300 550);
PAINT WHITE (-5300 550);
FORCEPROP 1 LAST SCH_NUMBER H4694802
J 0
(1350 650);
DISPLAY 1.212766 (1350 650);
PAINT YELLOW (1350 650);
FORCEPROP 1 LAST SCH_DEPT BESD
J 1
(-1800 600);
DISPLAY 1.212766 (-1800 600);
PAINT YELLOW (-1800 600);
FORCEPROP 1 LAST SCH_REV 2.420
J 0
(2400 650);
DISPLAY 0.978723 (2400 650);
PAINT YELLOW (2400 650);
FORCEPROP 2 LAST CDS_LIB mstr_symbols
J 0
(2650 500);
DISPLAY 0.787234 (2650 500);
PAINT MONO (2650 500);
DISPLAY INVISIBLE (2650 500);
FORCEPROP 2 LAST PAGE_BORDER TRUE
J 0
(-5240 5750);
DISPLAY 0.680851 (-5240 5750);
PAINT PINK (-5240 5750);
DISPLAY INVISIBLE (-5240 5750);
FORCEPROP 1 LAST COMMENT_BODY TRUE
J 0
(2660 510);
DISPLAY 0.382979 (2660 510);
PAINT GREEN (2660 510);
DISPLAY INVISIBLE (2660 510);
FORCEPROP 2 LAST CDS_XR_PAGE_TITLE CR-51 : @BASEBOARD_FAB2_LIB.BASEBOARD_FAB2(SCH_1):PAGE51
J 0
(-5240 5750);
DISPLAY 0.638298 (-5240 5750);
PAINT PINK (-5240 5750);
DISPLAY INVISIBLE (-5240 5750);
WIRE 17 -1 (750 5175)(750 5200);
WIRE 17 -1 (750 5075)(750 5175);
WIRE 17 -1 (1550 5200)(750 5200);
FORCEPROP 2 LAST SIG_NAME M_E_DQS_DP<17:0>
J 0
(1000 5210);
DISPLAY 0.617021 (1000 5210);
PAINT ORANGE (1000 5210);
WIRE 17 -1 (950 4425)(950 4525);
WIRE 17 -1 (950 4325)(950 4425);
WIRE 17 -1 (950 4525)(950 4625);
WIRE 17 -1 (950 4625)(950 4725);
WIRE 17 -1 (950 4225)(950 4325);
WIRE 17 -1 (950 4125)(950 4225);
WIRE 17 -1 (950 4725)(950 4825);
WIRE 17 -1 (950 4825)(950 4925);
WIRE 17 -1 (950 4025)(950 4125);
WIRE 17 -1 (950 3925)(950 4025);
WIRE 17 -1 (950 4925)(950 5025);
WIRE 17 -1 (950 5025)(950 5125);
WIRE 17 -1 (950 3825)(950 3925);
WIRE 17 -1 (950 3725)(950 3825);
WIRE 17 -1 (950 5125)(950 5150);
WIRE 17 -1 (1550 5150)(950 5150);
FORCEPROP 2 LAST SIG_NAME M_E_DQS_DN<17:0>
J 0
(1000 5160);
DISPLAY 0.617021 (1000 5160);
PAINT ORANGE (1000 5160);
WIRE 17 -1 (750 4475)(750 4575);
WIRE 17 -1 (750 4375)(750 4475);
WIRE 17 -1 (750 4575)(750 4675);
WIRE 17 -1 (750 4675)(750 4775);
WIRE 17 -1 (750 4275)(750 4375);
WIRE 17 -1 (750 4175)(750 4275);
WIRE 17 -1 (750 4775)(750 4875);
WIRE 17 -1 (750 4875)(750 4975);
WIRE 17 -1 (750 4075)(750 4175);
WIRE 17 -1 (750 3975)(750 4075);
WIRE 17 -1 (750 4975)(750 5075);
WIRE 17 -1 (750 3875)(750 3975);
WIRE 17 -1 (750 3775)(750 3875);
WIRE 17 -1 (950 3625)(950 3725);
WIRE 17 -1 (950 3525)(950 3625);
WIRE 17 -1 (950 3425)(950 3525);
WIRE 17 -1 (750 3675)(750 3775);
WIRE 17 -1 (750 3575)(750 3675);
WIRE 17 -1 (750 3475)(750 3575);
WIRE 17 -1 (-1550 4775)(-1550 4825);
WIRE 17 -1 (-1550 4725)(-1550 4775);
WIRE 17 -1 (-1550 4825)(-1550 4875);
WIRE 17 -1 (-1550 4875)(-1550 4925);
WIRE 17 -1 (-1550 4675)(-1550 4725);
WIRE 17 -1 (-1550 4625)(-1550 4675);
WIRE 17 -1 (-1550 4925)(-1550 4950);
WIRE 17 -1 (-1100 4950)(-1550 4950);
FORCEPROP 2 LAST SIG_NAME M_E_DQ<63:0>
J 0
(-1510 4960);
DISPLAY 0.617021 (-1510 4960);
PAINT ORANGE (-1510 4960);
WIRE 17 -1 (-1550 4575)(-1550 4625);
WIRE 17 -1 (-1550 4525)(-1550 4575);
WIRE 17 -1 (-1550 4475)(-1550 4525);
WIRE 17 -1 (-1550 4425)(-1550 4475);
WIRE 17 -1 (-1550 4375)(-1550 4425);
WIRE 17 -1 (-1550 4325)(-1550 4375);
WIRE 17 -1 (-1550 4275)(-1550 4325);
WIRE 17 -1 (-1550 4225)(-1550 4275);
WIRE 17 -1 (-1550 4175)(-1550 4225);
WIRE 17 -1 (-1550 4125)(-1550 4175);
WIRE 17 -1 (-1550 4075)(-1550 4125);
WIRE 17 -1 (-1550 4025)(-1550 4075);
WIRE 17 -1 (-1550 3975)(-1550 4025);
WIRE 17 -1 (-1550 3925)(-1550 3975);
WIRE 17 -1 (-1550 3875)(-1550 3925);
WIRE 17 -1 (-1550 3825)(-1550 3875);
WIRE 17 -1 (-1550 3775)(-1550 3825);
WIRE 17 -1 (-1550 3725)(-1550 3775);
WIRE 17 -1 (-1550 3675)(-1550 3725);
WIRE 17 -1 (-1550 3625)(-1550 3675);
WIRE 17 -1 (-1550 3575)(-1550 3625);
WIRE 17 -1 (-1550 3525)(-1550 3575);
WIRE 17 -1 (-1550 3475)(-1550 3525);
WIRE 17 -1 (-1550 3425)(-1550 3475);
WIRE 17 -1 (-1550 3375)(-1550 3425);
WIRE 17 -1 (-1550 3325)(-1550 3375);
WIRE 17 -1 (-1550 3275)(-1550 3325);
WIRE 17 -1 (-3150 4875)(-3150 4925);
WIRE 17 -1 (-3150 4825)(-3150 4875);
WIRE 17 -1 (-3150 4925)(-3150 4950);
WIRE 17 -1 (-3850 4950)(-3150 4950);
FORCEPROP 2 LAST SIG_NAME M_E_MA<17:0>
J 0
(-3800 4960);
DISPLAY 0.617021 (-3800 4960);
PAINT ORANGE (-3800 4960);
WIRE 17 -1 (-3150 4675)(-3150 4725);
WIRE 17 -1 (-3150 4625)(-3150 4675);
WIRE 17 -1 (-3150 4725)(-3150 4775);
WIRE 17 -1 (-3150 4775)(-3150 4825);
WIRE 17 -1 (-3150 4575)(-3150 4625);
WIRE 17 -1 (-3150 4525)(-3150 4575);
WIRE 17 -1 (-3150 4475)(-3150 4525);
WIRE 17 -1 (-3150 4425)(-3150 4475);
WIRE 17 -1 (-3150 4375)(-3150 4425);
WIRE 17 -1 (-3150 4325)(-3150 4375);
WIRE 17 -1 (-3150 4275)(-3150 4325);
WIRE 17 -1 (-3150 4225)(-3150 4275);
WIRE 17 -1 (-3150 4175)(-3150 4225);
WIRE 17 -1 (-3150 4125)(-3150 4175);
WIRE 17 -1 (-3150 4075)(-3150 4125);
WIRE 17 -1 (-1550 3225)(-1550 3275);
WIRE 17 -1 (-1550 3175)(-1550 3225);
WIRE 17 -1 (-1550 3125)(-1550 3175);
WIRE 17 -1 (-1550 3075)(-1550 3125);
WIRE 17 -1 (-1550 3025)(-1550 3075);
WIRE 17 -1 (-1550 2975)(-1550 3025);
WIRE 17 -1 (-1550 2925)(-1550 2975);
WIRE 17 -1 (-1550 2875)(-1550 2925);
WIRE 17 -1 (-1550 2825)(-1550 2875);
WIRE 17 -1 (-1550 2775)(-1550 2825);
WIRE 17 -1 (-1550 2725)(-1550 2775);
WIRE 17 -1 (-1550 2675)(-1550 2725);
WIRE 17 -1 (-1550 2625)(-1550 2675);
WIRE 17 -1 (-1550 2575)(-1550 2625);
WIRE 17 -1 (-1550 2525)(-1550 2575);
WIRE 17 -1 (-1550 2475)(-1550 2525);
WIRE 17 -1 (-1550 2425)(-1550 2475);
WIRE 17 -1 (-1550 2375)(-1550 2425);
WIRE 17 -1 (-1550 2325)(-1550 2375);
WIRE 17 -1 (-1550 2275)(-1550 2325);
WIRE 17 -1 (-1550 2225)(-1550 2275);
WIRE 17 -1 (-1550 2175)(-1550 2225);
WIRE 17 -1 (-1550 2125)(-1550 2175);
WIRE 17 -1 (-1550 2075)(-1550 2125);
WIRE 17 -1 (-1550 2025)(-1550 2075);
WIRE 17 -1 (-1550 1975)(-1550 2025);
WIRE 17 -1 (-1550 1925)(-1550 1975);
WIRE 17 -1 (-1550 1875)(-1550 1925);
WIRE 17 -1 (-1550 1825)(-1550 1875);
WIRE 17 -1 (-1550 1775)(-1550 1825);
WIRE 17 -1 (-3150 4050)(-3150 3975);
WIRE 17 -1 (-3150 4050)(-3850 4050);
FORCEPROP 2 LAST SIG_NAME M_E_BA<1:0>
J 0
(-3800 4060);
DISPLAY 0.617021 (-3800 4060);
PAINT ORANGE (-3800 4060);
WIRE 17 -1 (-3150 3875)(-3150 3900);
WIRE 17 -1 (-3150 3825)(-3150 3875);
WIRE 17 -1 (-3150 3900)(-3850 3900);
FORCEPROP 2 LAST SIG_NAME M_E_BG<1:0>
J 0
(-3800 3910);
DISPLAY 0.617021 (-3800 3910);
PAINT ORANGE (-3800 3910);
WIRE 17 -1 (-3150 3925)(-3150 3975);
WIRE 17 -1 (-3150 3375)(-3150 3425);
WIRE 17 -1 (-3150 3325)(-3150 3375);
WIRE 17 -1 (-3150 3425)(-3150 3450);
WIRE 17 -1 (-3150 3450)(-3850 3450);
FORCEPROP 2 LAST SIG_NAME M_E_CS_N<7:0>
J 0
(-3825 3460);
DISPLAY 0.617021 (-3825 3460);
PAINT ORANGE (-3825 3460);
WIRE 17 -1 (-3150 3275)(-3150 3325);
WIRE 17 -1 (-3150 2825)(-3150 2875);
WIRE 17 -1 (-3150 2775)(-3150 2825);
WIRE 17 -1 (-3150 2875)(-3150 2900);
WIRE 17 -1 (-3150 2900)(-3850 2900);
FORCEPROP 2 LAST SIG_NAME M_E_ECC<7:0>
J 0
(-3825 2910);
DISPLAY 0.617021 (-3825 2910);
PAINT ORANGE (-3825 2910);
WIRE 17 -1 (-3150 2975)(-3150 3025);
WIRE 17 -1 (-3150 3025)(-3150 3050);
WIRE 17 -1 (-3150 3050)(-3850 3050);
FORCEPROP 2 LAST SIG_NAME M_E_ODT<3:0>
J 0
(-3825 3060);
DISPLAY 0.617021 (-3825 3060);
PAINT ORANGE (-3825 3060);
WIRE 17 -1 (-3150 2725)(-3150 2775);
WIRE 17 -1 (-3150 2675)(-3150 2725);
WIRE 17 -1 (-3150 2625)(-3150 2675);
WIRE 17 -1 (-3150 2575)(-3150 2625);
WIRE 17 -1 (-3150 2525)(-3150 2575);
WIRE 17 -1 (-3700 3675)(-3700 3750);
WIRE 17 -1 (-3700 3575)(-3700 3675);
WIRE 17 -1 (-3700 3750)(-4150 3750);
FORCEPROP 2 LAST SIG_NAME M_E_CLK_DN<3:0>
J 0
(-4125 3760);
DISPLAY 0.617021 (-4125 3760);
PAINT ORANGE (-4125 3760);
WIRE 17 -1 (-3550 3725)(-3550 3625);
WIRE 17 -1 (-3550 3800)(-3550 3725);
WIRE 17 -1 (-3550 3800)(-4150 3800);
FORCEPROP 2 LAST SIG_NAME M_E_CLK_DP<3:0>
J 0
(-4125 3810);
DISPLAY 0.617021 (-4125 3810);
PAINT ORANGE (-4125 3810);
WIRE 17 -1 (-3200 3175)(-3200 3200);
WIRE 17 -1 (-3200 3125)(-3200 3175);
WIRE 17 -1 (-3200 3200)(-3850 3200);
FORCEPROP 2 LAST SIG_NAME M_E_CKE<3:0>
J 0
(-3825 3210);
DISPLAY 0.617021 (-3825 3210);
PAINT ORANGE (-3825 3210);
WIRE 16 -1 (-850 1200)(-650 1200);
WIRE 16 -1 (-850 1250)(-850 1200);
WIRE 16 -1 (-850 1250)(-650 1250);
WIRE 16 -1 (-850 1250)(-850 1300);
WIRE 16 -1 (-850 1300)(-650 1300);
WIRE 16 -1 (-850 1300)(-850 1350);
WIRE 16 -1 (-850 1350)(-650 1350);
WIRE 16 -1 (-850 1350)(-850 1400);
WIRE 16 -1 (-850 1400)(-650 1400);
WIRE 16 -1 (-850 1400)(-850 1450);
WIRE 16 -1 (-850 1450)(-650 1450);
WIRE 16 -1 (-850 1450)(-850 1500);
WIRE 16 -1 (-850 1500)(-850 1550);
WIRE 16 -1 (-850 1500)(-650 1500);
WIRE 16 -1 (-850 1550)(-650 1550);
WIRE 16 -1 (-850 1550)(-850 1600);
WIRE 16 -1 (-850 1600)(-650 1600);
WIRE 16 -1 (-850 1600)(-850 1650);
WIRE 16 -1 (-850 1650)(-650 1650);
WIRE 16 -1 (-850 1650)(-850 1700);
WIRE 16 -1 (-850 1700)(-650 1700);
WIRE 16 -1 (-850 1700)(-850 1750);
WIRE 16 -1 (-850 1750)(-650 1750);
WIRE 16 -1 (-850 1750)(-850 1800);
WIRE 16 -1 (-850 1800)(-650 1800);
WIRE 16 -1 (-850 1800)(-850 1850);
WIRE 16 -1 (-850 1850)(-650 1850);
WIRE 16 -1 (-850 1850)(-850 1900);
WIRE 16 -1 (-850 1900)(-650 1900);
WIRE 16 -1 (-850 1900)(-850 1950);
WIRE 16 -1 (-850 1950)(-650 1950);
WIRE 16 -1 (-850 1950)(-850 2000);
WIRE 16 -1 (-850 2000)(-850 2050);
WIRE 16 -1 (-850 2000)(-650 2000);
WIRE 16 -1 (-850 2050)(-650 2050);
WIRE 16 -1 (-850 2050)(-850 2100);
WIRE 16 -1 (-850 2100)(-650 2100);
WIRE 16 -1 (-850 2100)(-850 2150);
WIRE 16 -1 (-850 2150)(-650 2150);
WIRE 16 -1 (-850 2150)(-850 2200);
WIRE 16 -1 (-850 2200)(-650 2200);
WIRE 16 -1 (-850 2200)(-850 2250);
WIRE 16 -1 (-850 2250)(-650 2250);
WIRE 16 -1 (-850 2250)(-850 2300);
WIRE 16 -1 (-850 2300)(-650 2300);
WIRE 16 -1 (-850 2300)(-850 2350);
WIRE 16 -1 (-850 2350)(-650 2350);
WIRE 16 -1 (-850 2350)(-850 2400);
WIRE 16 -1 (-850 2400)(-650 2400);
WIRE 16 -1 (-850 2400)(-850 2450);
WIRE 16 -1 (-850 2450)(-650 2450);
WIRE 16 -1 (-1225 2450)(-850 2450);
WIRE 16 -1 (-1225 2550)(-1225 2450);
WIRE 16 -1 (2500 3600)(2500 3650);
WIRE 16 -1 (2500 3600)(2300 3600);
WIRE 16 -1 (2500 3550)(2500 3600);
WIRE 16 -1 (2500 3650)(2300 3650);
WIRE 16 -1 (2500 3500)(2500 3550);
WIRE 16 -1 (2500 3550)(2300 3550);
WIRE 16 -1 (2500 3450)(2500 3500);
WIRE 16 -1 (2500 3500)(2300 3500);
WIRE 16 -1 (2500 3400)(2500 3450);
WIRE 16 -1 (2500 3450)(2300 3450);
WIRE 16 -1 (2500 3350)(2500 3400);
WIRE 16 -1 (2500 3400)(2300 3400);
WIRE 16 -1 (2500 3300)(2500 3350);
WIRE 16 -1 (2500 3350)(2300 3350);
WIRE 16 -1 (2500 3250)(2500 3300);
WIRE 16 -1 (2500 3300)(2300 3300);
WIRE 16 -1 (2500 3200)(2500 3250);
WIRE 16 -1 (2500 3250)(2300 3250);
WIRE 16 -1 (2500 3150)(2500 3200);
WIRE 16 -1 (2500 3200)(2300 3200);
WIRE 16 -1 (2500 3100)(2500 3150);
WIRE 16 -1 (2500 3150)(2300 3150);
WIRE 16 -1 (2500 3100)(2300 3100);
WIRE 16 -1 (2500 3050)(2500 3100);
WIRE 16 -1 (2500 3000)(2500 3050);
WIRE 16 -1 (2500 3050)(2300 3050);
WIRE 16 -1 (2500 2950)(2500 3000);
WIRE 16 -1 (2500 3000)(2300 3000);
WIRE 16 -1 (2500 2900)(2500 2950);
WIRE 16 -1 (2500 2950)(2300 2950);
WIRE 16 -1 (2500 2850)(2500 2900);
WIRE 16 -1 (2500 2900)(2300 2900);
WIRE 16 -1 (2500 2800)(2500 2850);
WIRE 16 -1 (2500 2850)(2300 2850);
WIRE 16 -1 (2500 2750)(2500 2800);
WIRE 16 -1 (2500 2800)(2300 2800);
WIRE 16 -1 (2500 2700)(2500 2750);
WIRE 16 -1 (2500 2750)(2300 2750);
WIRE 16 -1 (2500 2650)(2500 2700);
WIRE 16 -1 (2500 2700)(2300 2700);
WIRE 16 -1 (2500 2600)(2500 2650);
WIRE 16 -1 (2500 2650)(2300 2650);
WIRE 16 -1 (2500 2600)(2300 2600);
WIRE 16 -1 (2500 2550)(2500 2600);
WIRE 16 -1 (2500 2500)(2500 2550);
WIRE 16 -1 (2500 2550)(2300 2550);
WIRE 16 -1 (2500 2450)(2500 2500);
WIRE 16 -1 (2500 2500)(2300 2500);
WIRE 16 -1 (2500 2400)(2500 2450);
WIRE 16 -1 (2500 2450)(2300 2450);
WIRE 16 -1 (2500 2350)(2500 2400);
WIRE 16 -1 (2500 2400)(2300 2400);
WIRE 16 -1 (2500 2300)(2500 2350);
WIRE 16 -1 (2500 2350)(2300 2350);
WIRE 16 -1 (2500 2250)(2500 2300);
WIRE 16 -1 (2500 2300)(2300 2300);
WIRE 16 -1 (2500 2200)(2500 2250);
WIRE 16 -1 (2500 2250)(2300 2250);
WIRE 16 -1 (2500 2150)(2500 2200);
WIRE 16 -1 (2500 2200)(2300 2200);
WIRE 16 -1 (2500 2100)(2500 2150);
WIRE 16 -1 (2500 2150)(2300 2150);
WIRE 16 -1 (2500 2050)(2500 2100);
WIRE 16 -1 (2500 2100)(2300 2100);
WIRE 16 -1 (2500 2050)(2300 2050);
WIRE 16 -1 (2500 2000)(2500 2050);
WIRE 16 -1 (2500 1950)(2500 2000);
WIRE 16 -1 (2500 2000)(2300 2000);
WIRE 16 -1 (2500 1900)(2500 1950);
WIRE 16 -1 (2500 1950)(2300 1950);
WIRE 16 -1 (2500 1850)(2500 1900);
WIRE 16 -1 (2500 1900)(2300 1900);
WIRE 16 -1 (2500 1800)(2500 1850);
WIRE 16 -1 (2500 1850)(2300 1850);
WIRE 16 -1 (2500 1750)(2500 1800);
WIRE 16 -1 (2500 1800)(2300 1800);
WIRE 16 -1 (2500 1700)(2500 1750);
WIRE 16 -1 (2500 1750)(2300 1750);
WIRE 16 -1 (2500 1650)(2500 1700);
WIRE 16 -1 (2500 1700)(2300 1700);
WIRE 16 -1 (2500 1600)(2500 1650);
WIRE 16 -1 (2500 1650)(2300 1650);
WIRE 16 -1 (2500 1550)(2500 1600);
WIRE 16 -1 (2500 1600)(2300 1600);
WIRE 16 -1 (2500 1550)(2300 1550);
WIRE 16 -1 (2500 1500)(2500 1550);
WIRE 16 -1 (2500 1450)(2500 1500);
WIRE 16 -1 (2500 1500)(2300 1500);
WIRE 16 -1 (2500 1400)(2500 1450);
WIRE 16 -1 (2500 1450)(2300 1450);
WIRE 16 -1 (2500 1350)(2500 1400);
WIRE 16 -1 (2500 1400)(2300 1400);
WIRE 16 -1 (2500 1250)(2500 1350);
WIRE 16 -1 (2500 1350)(2300 1350);
WIRE 16 -1 (-650 2550)(-850 2550);
WIRE 16 -1 (-850 2550)(-850 2600);
WIRE 16 -1 (-850 2600)(-650 2600);
WIRE 16 -1 (-1000 2600)(-850 2600);
WIRE 16 -1 (-1000 2700)(-1000 2600);
WIRE 16 -1 (-2850 2050)(-3250 2050);
WIRE 16 -1 (-3250 2050)(-3250 1950);
WIRE 16 -1 (-2850 1950)(-3250 1950);
WIRE 16 -1 (-3250 1950)(-5200 1950);
WIRE 16 -1 (-5200 1950)(-5200 1850);
WIRE 16 -1 (-4650 1350)(-4650 1450);
WIRE 16 -1 (-850 2700)(-650 2700);
WIRE 16 -1 (-850 2750)(-850 2700);
WIRE 16 -1 (-850 2750)(-650 2750);
WIRE 16 -1 (-850 2800)(-850 2750);
WIRE 16 -1 (-650 2800)(-850 2800);
WIRE 16 -1 (-850 2850)(-850 2800);
WIRE 16 -1 (-850 2850)(-650 2850);
WIRE 16 -1 (-850 2900)(-850 2850);
WIRE 16 -1 (-850 2900)(-650 2900);
WIRE 16 -1 (-850 3000)(-850 2900);
WIRE 16 -1 (-2850 2000)(-3100 2000);
WIRE 16 -1 (-3100 2000)(-3100 2100);
WIRE 16 -1 (-2850 2100)(-3100 2100);
WIRE 16 -1 (-3100 2100)(-5200 2100);
WIRE 16 -1 (-5200 2100)(-5200 2200);
WIRE 16 -1 (550 2850)(550 2900);
WIRE 16 -1 (550 2850)(350 2850);
WIRE 16 -1 (550 2900)(550 3075);
WIRE 16 -1 (550 2900)(350 2900);
WIRE 16 -1 (1100 3650)(1300 3650);
WIRE 16 -1 (1100 3600)(1100 3650);
WIRE 16 -1 (1100 3600)(1300 3600);
WIRE 16 -1 (1100 3550)(1100 3600);
WIRE 16 -1 (1100 3550)(1300 3550);
WIRE 16 -1 (1100 3500)(1100 3550);
WIRE 16 -1 (1100 3500)(1300 3500);
WIRE 16 -1 (1100 3450)(1100 3500);
WIRE 16 -1 (1100 3450)(1300 3450);
WIRE 16 -1 (1100 3400)(1100 3450);
WIRE 16 -1 (1100 3400)(1300 3400);
WIRE 16 -1 (1100 3350)(1100 3400);
WIRE 16 -1 (1100 3350)(1300 3350);
WIRE 16 -1 (1100 3300)(1100 3350);
WIRE 16 -1 (1100 3300)(1300 3300);
WIRE 16 -1 (1100 3250)(1100 3300);
WIRE 16 -1 (1100 3250)(1300 3250);
WIRE 16 -1 (1100 3200)(1100 3250);
WIRE 16 -1 (1100 3200)(1300 3200);
WIRE 16 -1 (1100 3150)(1100 3200);
WIRE 16 -1 (1100 3150)(1300 3150);
WIRE 16 -1 (1100 3100)(1100 3150);
WIRE 16 -1 (1100 3100)(1300 3100);
WIRE 16 -1 (1100 3050)(1100 3100);
WIRE 16 -1 (1100 3050)(1300 3050);
WIRE 16 -1 (1100 3000)(1100 3050);
WIRE 16 -1 (1100 3000)(1300 3000);
WIRE 16 -1 (1100 2950)(1100 3000);
WIRE 16 -1 (1100 2950)(1300 2950);
WIRE 16 -1 (1100 2900)(1100 2950);
WIRE 16 -1 (1100 2900)(1300 2900);
WIRE 16 -1 (1100 2850)(1100 2900);
WIRE 16 -1 (1100 2850)(1300 2850);
WIRE 16 -1 (1100 2800)(1100 2850);
WIRE 16 -1 (1100 2800)(1300 2800);
WIRE 16 -1 (1100 2750)(1100 2800);
WIRE 16 -1 (1100 2750)(1300 2750);
WIRE 16 -1 (1100 2700)(1100 2750);
WIRE 16 -1 (1100 2700)(1300 2700);
WIRE 16 -1 (1100 2650)(1100 2700);
WIRE 16 -1 (1100 2650)(1300 2650);
WIRE 16 -1 (1100 2600)(1100 2650);
WIRE 16 -1 (1100 2600)(1300 2600);
WIRE 16 -1 (1100 2550)(1100 2600);
WIRE 16 -1 (1100 2550)(1300 2550);
WIRE 16 -1 (1100 2500)(1100 2550);
WIRE 16 -1 (1100 2500)(1300 2500);
WIRE 16 -1 (1100 2450)(1100 2500);
WIRE 16 -1 (1100 2450)(1300 2450);
WIRE 16 -1 (1100 2400)(1100 2450);
WIRE 16 -1 (1100 2400)(1300 2400);
WIRE 16 -1 (1100 2350)(1100 2400);
WIRE 16 -1 (1100 2350)(1300 2350);
WIRE 16 -1 (1100 2300)(1100 2350);
WIRE 16 -1 (1100 2300)(1300 2300);
WIRE 16 -1 (1100 2250)(1100 2300);
WIRE 16 -1 (1100 2250)(1300 2250);
WIRE 16 -1 (1100 2200)(1100 2250);
WIRE 16 -1 (1100 2200)(1300 2200);
WIRE 16 -1 (1100 2150)(1100 2200);
WIRE 16 -1 (1100 2150)(1300 2150);
WIRE 16 -1 (1100 2100)(1100 2150);
WIRE 16 -1 (1100 2100)(1300 2100);
WIRE 16 -1 (1100 2050)(1100 2100);
WIRE 16 -1 (1100 2050)(1300 2050);
WIRE 16 -1 (1100 2000)(1100 2050);
WIRE 16 -1 (1100 2000)(1300 2000);
WIRE 16 -1 (1100 1950)(1100 2000);
WIRE 16 -1 (1100 1950)(1300 1950);
WIRE 16 -1 (1100 1900)(1100 1950);
WIRE 16 -1 (1100 1900)(1300 1900);
WIRE 16 -1 (1100 1850)(1100 1900);
WIRE 16 -1 (1100 1850)(1300 1850);
WIRE 16 -1 (1100 1800)(1100 1850);
WIRE 16 -1 (1100 1800)(1300 1800);
WIRE 16 -1 (1100 1750)(1100 1800);
WIRE 16 -1 (1100 1750)(1300 1750);
WIRE 16 -1 (1100 1700)(1100 1750);
WIRE 16 -1 (1100 1700)(1300 1700);
WIRE 16 -1 (1100 1650)(1100 1700);
WIRE 16 -1 (1100 1650)(1300 1650);
WIRE 16 -1 (1100 1600)(1100 1650);
WIRE 16 -1 (1100 1600)(1300 1600);
WIRE 16 -1 (1100 1550)(1100 1600);
WIRE 16 -1 (1100 1550)(1300 1550);
WIRE 16 -1 (1100 1500)(1100 1550);
WIRE 16 -1 (1100 1500)(1300 1500);
WIRE 16 -1 (1100 1450)(1100 1500);
WIRE 16 -1 (1100 1450)(1300 1450);
WIRE 16 -1 (1100 1400)(1100 1450);
WIRE 16 -1 (1100 1400)(1300 1400);
WIRE 16 -1 (1100 1350)(1100 1400);
WIRE 16 -1 (1100 1350)(1300 1350);
WIRE 16 -1 (1100 1250)(1100 1350);
WIRE 16 -1 (-2850 1750)(-4650 1750);
FORCEPROP 2 LAST SIG_NAME M_E_VREF
J 0
(-3600 1760);
DISPLAY 0.617021 (-3600 1760);
PAINT ORANGE (-3600 1760);
WIRE 16 -1 (-4650 1750)(-4650 1650);
WIRE 16 -1 (-4750 1750)(-4650 1750);
WIRE 16 -1 (-3700 1600)(-2850 1600);
FORCEPROP 2 LAST SIG_NAME TP_CH_E_DIMM_E0_RFU_1
J 0
(-3650 1610);
DISPLAY 0.617021 (-3650 1610);
PAINT ORANGE (-3650 1610);
FORCEPROP 2 LASTPROP $XRERR UNIQUE?
J 0
(-3940 1600);
DISPLAY 0.638298 (-3940 1600);
PAINT MONO (-3940 1600);
DISPLAY INVISIBLE (-3940 1600);
WIRE 16 -1 (-3700 1550)(-2850 1550);
FORCEPROP 2 LAST SIG_NAME TP_CH_E_DIMM_E0_RFU_0
J 0
(-3650 1560);
DISPLAY 0.617021 (-3650 1560);
PAINT ORANGE (-3650 1560);
FORCEPROP 2 LASTPROP $XRERR UNIQUE?
J 0
(-3940 1550);
DISPLAY 0.638298 (-3940 1550);
PAINT MONO (-3940 1550);
DISPLAY INVISIBLE (-3940 1550);
WIRE 16 -1 (-3700 1650)(-2850 1650);
FORCEPROP 2 LAST SIG_NAME TP_CH_E_DIMM_E0_RFU_2
J 0
(-3650 1660);
DISPLAY 0.617021 (-3650 1660);
PAINT ORANGE (-3650 1660);
FORCEPROP 2 LASTPROP $XRERR UNIQUE?
J 0
(-3940 1650);
DISPLAY 0.638298 (-3940 1650);
PAINT MONO (-3940 1650);
DISPLAY INVISIBLE (-3940 1650);
WIRE 16 -1 (-3650 1850)(-2850 1850);
FORCEPROP 2 LAST SIG_NAME SMB_DDR_DEF_VPP_SCL
J 0
(-3610 1860);
DISPLAY 0.617021 (-3610 1860);
PAINT ORANGE (-3610 1860);
WIRE 16 -1 (-2850 1900)(-3650 1900);
WIRE 16 -1 (-3700 1450)(-2850 1450);
FORCEPROP 2 LAST SIG_NAME FM_ADR_COMPLETE_DEF_N
J 0
(-3650 1460);
DISPLAY 0.617021 (-3650 1460);
PAINT ORANGE (-3650 1460);
WIRE 16 -1 (-3300 2300)(-2850 2300);
WIRE 16 -1 (-3300 2300)(-3300 2600);
WIRE 16 -1 (-3300 2600)(-4025 2600);
FORCEPROP 2 LAST SIG_NAME FM_DIMM_EVENT_COD_N
J 0
(-3958 2624);
DISPLAY 0.617021 (-3958 2624);
PAINT ORANGE (-3958 2624);
WIRE 16 -1 (-2850 2350)(-3250 2350);
WIRE 16 -1 (-3250 2350)(-3250 2800);
WIRE 16 -1 (-3250 2800)(-3850 2800);
FORCEPROP 2 LAST SIG_NAME M_DEF_RST_N
J 0
(-3825 2810);
DISPLAY 0.617021 (-3825 2810);
PAINT ORANGE (-3825 2810);
WIRE 16 -1 (-2850 2400)(-3200 2400);
WIRE 16 -1 (-3200 2400)(-3200 2850);
WIRE 16 -1 (-3200 2850)(-3850 2850);
FORCEPROP 2 LAST SIG_NAME M_E_PAR
J 0
(-3825 2860);
DISPLAY 0.617021 (-3825 2860);
PAINT ORANGE (-3825 2860);
WIRE 16 -1 (-2850 3100)(-3100 3100);
WIRE 16 -1 (-2850 3700)(-3450 3700);
WIRE 16 -1 (-2850 3150)(-3100 3150);
WIRE 16 -1 (-2850 3600)(-3450 3600);
WIRE 16 -1 (-2850 3550)(-3600 3550);
WIRE 16 -1 (-2850 3650)(-3600 3650);
WIRE 16 -1 (-2850 2200)(-3850 2200);
FORCEPROP 2 LAST SIG_NAME M_E_ACT_N
J 0
(-3800 2210);
DISPLAY 0.617021 (-3800 2210);
PAINT ORANGE (-3800 2210);
WIRE 16 -1 (-2850 2250)(-3875 2250);
FORCEPROP 2 LAST SIG_NAME M_E_ALERT_N
J 0
(-3825 2260);
DISPLAY 0.617021 (-3825 2260);
PAINT ORANGE (-3825 2260);
WIRE 16 -1 (-2850 2500)(-3050 2500);
WIRE 16 -1 (-2850 2550)(-3050 2550);
WIRE 16 -1 (-2850 2600)(-3050 2600);
WIRE 16 -1 (-2850 2650)(-3050 2650);
WIRE 16 -1 (-2850 2700)(-3050 2700);
WIRE 16 -1 (-2850 2750)(-3050 2750);
WIRE 16 -1 (-2850 2800)(-3050 2800);
WIRE 16 -1 (-2850 3000)(-3050 3000);
WIRE 16 -1 (-2850 2950)(-3050 2950);
WIRE 16 -1 (-2850 2850)(-3050 2850);
WIRE 16 -1 (-2850 3250)(-3050 3250);
WIRE 16 -1 (-2850 3300)(-3050 3300);
WIRE 16 -1 (-3000 3450)(-2850 3450);
WIRE 16 -1 (-3000 3500)(-3000 3450);
WIRE 16 -1 (-3000 3500)(-3850 3500);
FORCEPROP 2 LAST SIG_NAME M_E_C<2>
J 0
(-3825 3510);
DISPLAY 0.617021 (-3825 3510);
PAINT ORANGE (-3825 3510);
WIRE 16 -1 (-2850 3350)(-3050 3350);
WIRE 16 -1 (-2850 3400)(-3050 3400);
WIRE 16 -1 (-2850 3800)(-3050 3800);
WIRE 16 -1 (-2850 3900)(-3050 3900);
WIRE 16 -1 (-2850 3850)(-3050 3850);
WIRE 16 -1 (-2850 4050)(-3050 4050);
WIRE 16 -1 (-2850 3950)(-3050 3950);
WIRE 16 -1 (-1650 2000)(-1850 2000);
WIRE 16 -1 (-1650 1950)(-1850 1950);
WIRE 16 -1 (-1650 1900)(-1850 1900);
WIRE 16 -1 (-1650 1850)(-1850 1850);
WIRE 16 -1 (-1650 1750)(-1850 1750);
WIRE 16 -1 (-1650 1800)(-1850 1800);
WIRE 16 -1 (-1650 2500)(-1850 2500);
WIRE 16 -1 (-1650 2050)(-1850 2050);
WIRE 16 -1 (-1650 2100)(-1850 2100);
WIRE 16 -1 (-1650 2150)(-1850 2150);
WIRE 16 -1 (-1650 2250)(-1850 2250);
WIRE 16 -1 (-1650 2300)(-1850 2300);
WIRE 16 -1 (-1650 2350)(-1850 2350);
WIRE 16 -1 (-1650 2450)(-1850 2450);
WIRE 16 -1 (-1650 2550)(-1850 2550);
WIRE 16 -1 (-1650 2200)(-1850 2200);
WIRE 16 -1 (-1650 2400)(-1850 2400);
WIRE 16 -1 (-1650 2600)(-1850 2600);
WIRE 16 -1 (-1650 3050)(-1850 3050);
WIRE 16 -1 (-1650 2650)(-1850 2650);
WIRE 16 -1 (-1650 2700)(-1850 2700);
WIRE 16 -1 (-1650 2750)(-1850 2750);
WIRE 16 -1 (-1650 2850)(-1850 2850);
WIRE 16 -1 (-1650 2900)(-1850 2900);
WIRE 16 -1 (-1650 2950)(-1850 2950);
WIRE 16 -1 (-1650 3000)(-1850 3000);
WIRE 16 -1 (-1650 2800)(-1850 2800);
WIRE 16 -1 (-1650 3100)(-1850 3100);
WIRE 16 -1 (-1650 3550)(-1850 3550);
WIRE 16 -1 (-1650 3500)(-1850 3500);
WIRE 16 -1 (-1650 3250)(-1850 3250);
WIRE 16 -1 (-1650 3300)(-1850 3300);
WIRE 16 -1 (-1650 3350)(-1850 3350);
WIRE 16 -1 (-1650 3400)(-1850 3400);
WIRE 16 -1 (-1650 3450)(-1850 3450);
WIRE 16 -1 (-1650 3150)(-1850 3150);
WIRE 16 -1 (-1650 3200)(-1850 3200);
WIRE 16 -1 (-1650 3650)(-1850 3650);
WIRE 16 -1 (-1650 3600)(-1850 3600);
WIRE 16 -1 (-1650 3700)(-1850 3700);
WIRE 16 -1 (-1650 3750)(-1850 3750);
WIRE 16 -1 (-1650 3800)(-1850 3800);
WIRE 16 -1 (-1650 3850)(-1850 3850);
WIRE 16 -1 (-1650 3900)(-1850 3900);
WIRE 16 -1 (-1650 3950)(-1850 3950);
WIRE 16 -1 (-1650 4000)(-1850 4000);
WIRE 16 -1 (-1650 4050)(-1850 4050);
WIRE 16 -1 (-2850 4150)(-3050 4150);
WIRE 16 -1 (-2850 4350)(-3050 4350);
WIRE 16 -1 (-2850 4300)(-3050 4300);
WIRE 16 -1 (-2850 4250)(-3050 4250);
WIRE 16 -1 (-2850 4200)(-3050 4200);
WIRE 16 -1 (-2850 4100)(-3050 4100);
WIRE 16 -1 (-2850 4600)(-3050 4600);
WIRE 16 -1 (-2850 4550)(-3050 4550);
WIRE 16 -1 (-2850 4500)(-3050 4500);
WIRE 16 -1 (-2850 4450)(-3050 4450);
WIRE 16 -1 (-2850 4400)(-3050 4400);
WIRE 16 -1 (-2850 4850)(-3050 4850);
WIRE 16 -1 (-2850 4800)(-3050 4800);
WIRE 16 -1 (-2850 4750)(-3050 4750);
WIRE 16 -1 (-2850 4700)(-3050 4700);
WIRE 16 -1 (-2850 4650)(-3050 4650);
WIRE 16 -1 (-2850 4900)(-3050 4900);
WIRE 16 -1 (-1650 4100)(-1850 4100);
WIRE 16 -1 (-1650 4150)(-1850 4150);
WIRE 16 -1 (-1650 4200)(-1850 4200);
WIRE 16 -1 (-1650 4250)(-1850 4250);
WIRE 16 -1 (-1650 4300)(-1850 4300);
WIRE 16 -1 (-1650 4350)(-1850 4350);
WIRE 16 -1 (-1650 4400)(-1850 4400);
WIRE 16 -1 (-1650 4450)(-1850 4450);
WIRE 16 -1 (-1650 4600)(-1850 4600);
WIRE 16 -1 (-1650 4500)(-1850 4500);
WIRE 16 -1 (-1650 4550)(-1850 4550);
WIRE 16 -1 (-1650 4900)(-1850 4900);
WIRE 16 -1 (-1650 4850)(-1850 4850);
WIRE 16 -1 (-1650 4800)(-1850 4800);
WIRE 16 -1 (-1650 4650)(-1850 4650);
WIRE 16 -1 (-1650 4700)(-1850 4700);
WIRE 16 -1 (-1650 4750)(-1850 4750);
WIRE 16 -1 (650 4050)(450 4050);
WIRE 16 -1 (850 4000)(450 4000);
WIRE 16 -1 (650 3950)(450 3950);
WIRE 16 -1 (850 3900)(450 3900);
WIRE 16 -1 (650 3850)(450 3850);
WIRE 16 -1 (850 3800)(450 3800);
WIRE 16 -1 (650 3750)(450 3750);
WIRE 16 -1 (850 3700)(450 3700);
WIRE 16 -1 (650 3650)(450 3650);
WIRE 16 -1 (850 3600)(450 3600);
WIRE 16 -1 (650 3550)(450 3550);
WIRE 16 -1 (850 3500)(450 3500);
WIRE 16 -1 (650 3450)(450 3450);
WIRE 16 -1 (850 3400)(450 3400);
WIRE 16 -1 (650 4350)(450 4350);
WIRE 16 -1 (850 4300)(450 4300);
WIRE 16 -1 (650 4250)(450 4250);
WIRE 16 -1 (850 4200)(450 4200);
WIRE 16 -1 (650 4150)(450 4150);
WIRE 16 -1 (850 4100)(450 4100);
WIRE 16 -1 (850 5100)(450 5100);
WIRE 16 -1 (650 5050)(450 5050);
WIRE 16 -1 (850 5000)(450 5000);
WIRE 16 -1 (650 4950)(450 4950);
WIRE 16 -1 (850 4900)(450 4900);
WIRE 16 -1 (650 4850)(450 4850);
WIRE 16 -1 (850 4800)(450 4800);
WIRE 16 -1 (650 4750)(450 4750);
WIRE 16 -1 (850 4700)(450 4700);
WIRE 16 -1 (650 4650)(450 4650);
WIRE 16 -1 (850 4600)(450 4600);
WIRE 16 -1 (650 4550)(450 4550);
WIRE 16 -1 (850 4500)(450 4500);
WIRE 16 -1 (650 4450)(450 4450);
WIRE 16 -1 (850 4400)(450 4400);
WIRE 16 -1 (650 5150)(450 5150);
DOT 1 (1100 1850);
DOT 1 (-850 2400);
DOT 1 (-850 1350);
DOT 1 (-850 1400);
DOT 1 (-850 1450);
DOT 1 (-850 2350);
DOT 1 (2500 2550);
DOT 1 (2500 2500);
DOT 1 (1100 1750);
DOT 1 (550 2900);
DOT 1 (-850 1950);
DOT 1 (-850 1250);
DOT 1 (-850 1300);
DOT 1 (-850 1500);
DOT 1 (-850 1600);
DOT 1 (-850 1700);
DOT 1 (-850 1650);
DOT 1 (-850 1750);
DOT 1 (-850 1850);
DOT 1 (-850 1800);
DOT 1 (-850 1900);
DOT 1 (-850 2100);
DOT 1 (-850 2150);
DOT 1 (-850 2200);
DOT 1 (-850 2250);
DOT 1 (-850 2300);
DOT 1 (-850 2600);
DOT 1 (-850 2750);
DOT 1 (-850 2800);
DOT 1 (2500 3600);
DOT 1 (2500 3550);
DOT 1 (2500 3500);
DOT 1 (2500 3350);
DOT 1 (2500 3450);
DOT 1 (2500 3400);
DOT 1 (2500 3300);
DOT 1 (2500 3250);
DOT 1 (2500 3200);
DOT 1 (2500 3100);
DOT 1 (2500 3150);
DOT 1 (2500 3000);
DOT 1 (2500 3050);
DOT 1 (2500 2950);
DOT 1 (2500 2900);
DOT 1 (2500 2850);
DOT 1 (2500 2750);
DOT 1 (2500 2800);
DOT 1 (2500 2700);
DOT 1 (2500 2650);
DOT 1 (2500 2600);
DOT 1 (2500 2450);
DOT 1 (2500 2400);
DOT 1 (2500 2350);
DOT 1 (2500 2200);
DOT 1 (2500 2300);
DOT 1 (2500 2250);
DOT 1 (2500 2100);
DOT 1 (2500 2150);
DOT 1 (2500 2050);
DOT 1 (2500 2000);
DOT 1 (2500 1950);
DOT 1 (2500 1850);
DOT 1 (2500 1900);
DOT 1 (2500 1800);
DOT 1 (2500 1750);
DOT 1 (2500 1700);
DOT 1 (2500 1650);
DOT 1 (2500 1600);
DOT 1 (2500 1550);
DOT 1 (2500 1500);
DOT 1 (2500 1450);
DOT 1 (2500 1400);
DOT 1 (2500 1350);
DOT 1 (1100 3600);
DOT 1 (1100 3550);
DOT 1 (1100 3500);
DOT 1 (1100 3450);
DOT 1 (1100 3400);
DOT 1 (1100 3300);
DOT 1 (1100 3250);
DOT 1 (1100 3200);
DOT 1 (1100 3150);
DOT 1 (1100 3100);
DOT 1 (1100 3050);
DOT 1 (1100 3000);
DOT 1 (1100 2950);
DOT 1 (1100 2900);
DOT 1 (1100 2850);
DOT 1 (1100 2800);
DOT 1 (1100 2750);
DOT 1 (1100 2650);
DOT 1 (1100 2600);
DOT 1 (1100 2550);
DOT 1 (1100 2500);
DOT 1 (1100 2450);
DOT 1 (1100 2400);
DOT 1 (1100 2350);
DOT 1 (1100 2300);
DOT 1 (1100 2250);
DOT 1 (1100 2200);
DOT 1 (1100 2150);
DOT 1 (1100 2100);
DOT 1 (1100 2050);
DOT 1 (1100 2000);
DOT 1 (1100 1950);
DOT 1 (1100 1900);
DOT 1 (1100 1800);
DOT 1 (1100 1700);
DOT 1 (1100 1650);
DOT 1 (1100 1600);
DOT 1 (1100 1550);
DOT 1 (1100 1500);
DOT 1 (1100 1450);
DOT 1 (1100 1400);
DOT 1 (1100 1350);
DOT 1 (-3100 2100);
DOT 1 (-4650 1750);
DOT 1 (-850 2850);
DOT 1 (1100 3350);
DOT 1 (-850 2050);
DOT 1 (-850 1550);
DOT 1 (1100 2700);
DOT 1 (-850 2900);
DOT 1 (-850 2450);
DOT 1 (-3250 1950);
DOT 1 (-850 2000);
FORCENOTE
SMBUS ADDR: 0XA4
(-5275 709) 0;
DISPLAY LEFT (-5275 709);
DISPLAY 1.957447 (-5275 709);
PAINT PURPLE (-5275 709);
FORCENOTE
PLACE CAP NEAR DIMM CONNECTOR
(-5263 1152) 0;
DISPLAY LEFT (-5263 1152);
DISPLAY 1.595745 (-5263 1152);
PAINT PURPLE (-5263 1152);
QUIT
